FILE_TYPE = MACRO_DRAWING;
SET COLOR_WIRE YELLOW;
SET COLOR_PROP ORANGE;
SET COLOR_DOT WHITE;
SET COLOR_ARC YELLOW;
SET COLOR_BODY GREEN;
SET COLOR_NOTE PURPLE;
SET PROP_DISPLAY VALUE;
SET PAGE_NUMBER P257;
FORCEADD UNIVERSAL_GND..1
(-4750 1675);
FORCEPROP 3 LASTPIN (-4750 1725) SIG_NAME GND\g
J 0
(-4740 1735);
DISPLAY 0.659574 (-4740 1735);
PAINT MONO (-4740 1735);
DISPLAY INVISIBLE (-4740 1735);
FORCEPROP 1 LAST HDL_POWER GND
J 1
(-4725 1600);
DISPLAY 0.872340 (-4725 1600);
PAINT GREEN (-4725 1600);
DISPLAY INVISIBLE (-4725 1600);
FORCEPROP 2 LAST CDS_LIB logical_power
J 0
(-4750 1675);
PAINT MONO (-4750 1675);
DISPLAY INVISIBLE (-4750 1675);
FORCEPROP 1 LAST PATH I1
J 0
(-4675 1675);
DISPLAY 0.872340 (-4675 1675);
PAINT AQUA (-4675 1675);
DISPLAY INVISIBLE (-4675 1675);
FORCEADD VCC15..1
(-4825 6925);
FORCEPROP 3 LASTPIN (-4825 6875) SIG_NAME P5V\g
J 0
(-4815 6885);
DISPLAY 0.659574 (-4815 6885);
PAINT MONO (-4815 6885);
DISPLAY INVISIBLE (-4815 6885);
FORCEPROP 1 LAST HDL_POWER P5V
J 1
(-4825 6975);
DISPLAY 0.617021 (-4825 6975);
PAINT GREEN (-4825 6975);
FORCEPROP 2 LAST CDS_LIB logical_power
J 0
(-4825 6925);
DISPLAY INVISIBLE (-4825 6925);
FORCEPROP 1 LAST PATH I10
J 0
(-4775 6950);
DISPLAY 0.872340 (-4775 6950);
PAINT AQUA (-4775 6950);
DISPLAY INVISIBLE (-4775 6950);
FORCEADD OFFPAGE..1
(-4275 1800);
FORCEPROP 2 LAST $XR0 266 
J 0
(-4527 1800);
DISPLAY 0.638298 (-4527 1800);
PAINT MONO (-4527 1800);
FORCEPROP 1 LAST COMMENT_BODY TRUE
J 0
(-4150 1700);
DISPLAY 0.872340 (-4150 1700);
PAINT GREEN (-4150 1700);
DISPLAY INVISIBLE (-4150 1700);
FORCEPROP 1 LAST OFFPAGE TRUE
J 0
(-3950 1675);
DISPLAY 0.872340 (-3950 1675);
PAINT GREEN (-3950 1675);
DISPLAY INVISIBLE (-3950 1675);
FORCEPROP 2 LAST CDS_LIB standard
J 0
(-4275 1800);
DISPLAY INVISIBLE (-4275 1800);
FORCEPROP 2 LAST PATH I11
J 0
(-4525 1850);
DISPLAY 1.021277 (-4525 1850);
DISPLAY INVISIBLE (-4525 1850);
FORCEADD OFFPAGE..5
(-4275 1900);
FORCEPROP 2 LAST $XR2 266 
J 0
(-4560 1936);
DISPLAY 0.638298 (-4560 1936);
PAINT MONO (-4560 1936);
FORCEPROP 2 LAST $XR1 272 
J 0
(-4560 1864);
DISPLAY 0.638298 (-4560 1864);
PAINT MONO (-4560 1864);
FORCEPROP 2 LAST $XR0 271 
J 0
(-4560 1900);
DISPLAY 0.638298 (-4560 1900);
PAINT MONO (-4560 1900);
FORCEPROP 1 LAST COMMENT_BODY TRUE
J 0
(-4175 1825);
DISPLAY 0.872340 (-4175 1825);
PAINT GREEN (-4175 1825);
DISPLAY INVISIBLE (-4175 1825);
FORCEPROP 1 LAST OFFPAGE TRUE
J 0
(-3950 1775);
DISPLAY 0.872340 (-3950 1775);
PAINT GREEN (-3950 1775);
DISPLAY INVISIBLE (-3950 1775);
FORCEPROP 2 LAST CDS_LIB standard
J 0
(-4275 1900);
DISPLAY INVISIBLE (-4275 1900);
FORCEPROP 2 LAST PATH I12
J 0
(-4550 1975);
DISPLAY 1.021277 (-4550 1975);
DISPLAY INVISIBLE (-4550 1975);
FORCEADD OFFPAGE..1
(-4275 2300);
FORCEPROP 2 LAST $XR6 272 
J 0
(-5247 2300);
DISPLAY 0.638298 (-5247 2300);
PAINT MONO (-5247 2300);
FORCEPROP 2 LAST $XR5 271 
J 0
(-5127 2300);
DISPLAY 0.638298 (-5127 2300);
PAINT MONO (-5127 2300);
FORCEPROP 2 LAST $XR4 270 
J 0
(-5007 2300);
DISPLAY 0.638298 (-5007 2300);
PAINT MONO (-5007 2300);
FORCEPROP 2 LAST $XR3 269 
J 0
(-4887 2300);
DISPLAY 0.638298 (-4887 2300);
PAINT MONO (-4887 2300);
FORCEPROP 2 LAST $XR2 268 
J 0
(-4767 2300);
DISPLAY 0.638298 (-4767 2300);
PAINT MONO (-4767 2300);
FORCEPROP 2 LAST $XR1 267 
J 0
(-4647 2300);
DISPLAY 0.638298 (-4647 2300);
PAINT MONO (-4647 2300);
FORCEPROP 2 LAST $XR0 266 
J 0
(-4527 2300);
DISPLAY 0.638298 (-4527 2300);
PAINT MONO (-4527 2300);
FORCEPROP 1 LAST COMMENT_BODY TRUE
J 0
(-4150 2200);
DISPLAY 0.872340 (-4150 2200);
PAINT GREEN (-4150 2200);
DISPLAY INVISIBLE (-4150 2200);
FORCEPROP 1 LAST OFFPAGE TRUE
J 0
(-3950 2175);
DISPLAY 0.872340 (-3950 2175);
PAINT GREEN (-3950 2175);
DISPLAY INVISIBLE (-3950 2175);
FORCEPROP 2 LAST CDS_LIB standard
J 0
(-4275 2300);
DISPLAY INVISIBLE (-4275 2300);
FORCEPROP 2 LAST PATH I13
J 0
(-4525 2350);
DISPLAY 1.021277 (-4525 2350);
DISPLAY INVISIBLE (-4525 2350);
FORCEADD OFFPAGE..5
(-4275 2400);
FORCEPROP 2 LAST $XR0 266 
J 0
(-4560 2400);
DISPLAY 0.638298 (-4560 2400);
PAINT MONO (-4560 2400);
FORCEPROP 1 LAST COMMENT_BODY TRUE
J 0
(-4175 2325);
DISPLAY 0.872340 (-4175 2325);
PAINT GREEN (-4175 2325);
DISPLAY INVISIBLE (-4175 2325);
FORCEPROP 1 LAST OFFPAGE TRUE
J 0
(-3950 2275);
DISPLAY 0.872340 (-3950 2275);
PAINT GREEN (-3950 2275);
DISPLAY INVISIBLE (-3950 2275);
FORCEPROP 2 LAST CDS_LIB standard
J 0
(-4275 2400);
DISPLAY INVISIBLE (-4275 2400);
FORCEPROP 2 LAST PATH I14
J 0
(-4550 2450);
DISPLAY 1.021277 (-4550 2450);
DISPLAY INVISIBLE (-4550 2450);
FORCEADD Q_CAP..2
(-3975 2200);
FORCEPROP 1 LAST PART_NUMBER CH4104K1B00
J 1
(-3700 2250);
DISPLAY 0.617021 (-3700 2250);
PAINT BLUE (-3700 2250);
DISPLAY INVISIBLE (-3700 2250);
FORCEPROP 1 LAST TOLERANCE 10%
J 2
(-3325 2225);
DISPLAY 0.617021 (-3325 2225);
PAINT SKYBLUE (-3325 2225);
FORCEPROP 1 LAST MATERIAL X7R
J 0
(-3500 2250);
DISPLAY 0.617021 (-3500 2250);
PAINT SKYBLUE (-3500 2250);
FORCEPROP 1 LAST PACK_TYPE 0402
J 1
(-3500 2200);
DISPLAY 0.617021 (-3500 2200);
PAINT SKYBLUE (-3500 2200);
FORCEPROP 1 LAST VOLTAGE 25V
J 0
(-3675 2200);
DISPLAY 0.617021 (-3675 2200);
PAINT SKYBLUE (-3675 2200);
FORCEPROP 1 LAST VALUE 0.1UF
J 2
(-3700 2200);
DISPLAY 0.617021 (-3700 2200);
PAINT SKYBLUE (-3700 2200);
FORCEPROP 1 LAST LOCATION PC1350
J 1
(-4175 2200);
DISPLAY 0.617021 (-4175 2200);
PAINT AQUA (-4175 2200);
FORCEPROP 1 LASTPIN (-4075 2200) $PN 1
J 0
(-4085 2215);
DISPLAY 0.617021 (-4085 2215);
FORCEPROP 1 LASTPIN (-3875 2200) $PN 2
J 0
(-3890 2215);
DISPLAY 0.617021 (-3890 2215);
FORCEPROP 2 LAST CDS_LIB pure_quanta
J 0
(-3975 2200);
PAINT MONO (-3975 2200);
DISPLAY INVISIBLE (-3975 2200);
FORCEPROP 1 LAST PATH I15
J 0
(-3975 2400);
DISPLAY 0.978723 (-3975 2400);
PAINT WHITE (-3975 2400);
DISPLAY INVISIBLE (-3975 2400);
FORCEPROP 2 LAST $SEC 1
J 0
(-3975 2450);
DISPLAY 0.680851 (-3975 2450);
PAINT MONO (-3975 2450);
DISPLAY INVISIBLE (-3975 2450);
FORCEPROP 2 LAST CDS_SEC 1
J 0
(-3975 2450);
DISPLAY 1.021277 (-3975 2450);
DISPLAY INVISIBLE (-3975 2450);
FORCEADD ISL99390FRZTR5935..1
(-2725 2400);
FORCEPROP 1 LAST PART_NUMBER AL099390004
J 0
(-3025 3200);
DISPLAY 0.617021 (-3025 3200);
PAINT BLUE (-3025 3200);
DISPLAY INVISIBLE (-3025 3200);
FORCEPROP 1 LAST MATERIAL IC
J 0
(-3025 3125);
DISPLAY 0.617021 (-3025 3125);
PAINT SKYBLUE (-3025 3125);
FORCEPROP 2 LAST VALUE ISL99390FRZ-TR5935
J 0
(-3025 3350);
DISPLAY 0.617021 (-3025 3350);
PAINT SKYBLUE (-3025 3350);
FORCEPROP 2 LAST PART_TYPE SMLF
J 0
(-3025 3400);
DISPLAY 0.638298 (-3025 3400);
FORCEPROP 1 LAST LOCATION PU70_P0_2
J 0
(-3025 3275);
DISPLAY 0.617021 (-3025 3275);
PAINT AQUA (-3025 3275);
FORCEPROP 2 LASTPIN (-2325 1950) $PN 2
J 0
(-2315 1960);
DISPLAY 0.617021 (-2315 1960);
PAINT MONO (-2315 1960);
FORCEPROP 2 LASTPIN (-2325 2750) $PN 33
J 0
(-2315 2760);
DISPLAY 0.617021 (-2315 2760);
PAINT MONO (-2315 2760);
FORCEPROP 2 LASTPIN (-3175 2150) $PN 31
J 2
(-3185 2160);
DISPLAY 0.617021 (-3185 2160);
PAINT MONO (-3185 2160);
FORCEPROP 2 LASTPIN (-3175 2550) $PN 35
J 2
(-3185 2560);
DISPLAY 0.617021 (-3185 2560);
PAINT MONO (-3185 2560);
FORCEPROP 2 LASTPIN (-2325 2100) $PN 6
J 0
(-2315 2110);
DISPLAY 0.617021 (-2315 2110);
PAINT MONO (-2315 2110);
FORCEPROP 2 LASTPIN (-2325 2050) $PN 41
J 0
(-2315 2060);
DISPLAY 0.617021 (-2315 2060);
PAINT MONO (-2315 2060);
FORCEPROP 2 LASTPIN (-3175 2400) $PN 38
J 2
(-3185 2410);
DISPLAY 0.617021 (-3185 2410);
PAINT MONO (-3185 2410);
FORCEPROP 2 LASTPIN (-3175 2100) $PN 37
J 2
(-3185 2110);
DISPLAY 0.617021 (-3185 2110);
PAINT MONO (-3185 2110);
FORCEPROP 2 LASTPIN (-2325 1900) $PN 5
J 0
(-2315 1910);
DISPLAY 0.617021 (-2315 1910);
PAINT MONO (-2315 1910);
FORCEPROP 2 LASTPIN (-2325 1850) $PN 7_9-20_24
J 0
(-2315 1860);
DISPLAY 0.617021 (-2315 1860);
PAINT MONO (-2315 1860);
FORCEPROP 2 LASTPIN (-2325 1800) $PN 40
J 0
(-2315 1810);
DISPLAY 0.617021 (-2315 1810);
PAINT MONO (-2315 1810);
FORCEPROP 2 LASTPIN (-2325 2500) $PN 32
J 0
(-2315 2510);
DISPLAY 0.617021 (-2315 2510);
PAINT MONO (-2315 2510);
FORCEPROP 2 LASTPIN (-3175 3050) $PN 4
J 2
(-3185 3060);
DISPLAY 0.617021 (-3185 3060);
PAINT MONO (-3185 3060);
FORCEPROP 2 LASTPIN (-3175 1800) $PN 34
J 2
(-3185 1810);
DISPLAY 0.617021 (-3185 1810);
PAINT MONO (-3185 1810);
FORCEPROP 2 LASTPIN (-3175 2300) $PN 39
J 2
(-3185 2310);
DISPLAY 0.617021 (-3185 2310);
PAINT MONO (-3185 2310);
FORCEPROP 2 LASTPIN (-2325 2400) $PN 10_19
J 0
(-2315 2410);
DISPLAY 0.617021 (-2315 2410);
PAINT MONO (-2315 2410);
FORCEPROP 2 LASTPIN (-3175 1900) $PN 36
J 2
(-3185 1910);
DISPLAY 0.617021 (-3185 1910);
PAINT MONO (-3185 1910);
FORCEPROP 2 LASTPIN (-3175 2750) $PN 3
J 2
(-3185 2760);
DISPLAY 0.617021 (-3185 2760);
PAINT MONO (-3185 2760);
FORCEPROP 2 LASTPIN (-2325 3050) $PN 25_29
J 0
(-2315 3060);
DISPLAY 0.617021 (-2315 3060);
PAINT MONO (-2315 3060);
FORCEPROP 2 LASTPIN (-2325 3000) $PN 30
J 0
(-2315 3010);
DISPLAY 0.617021 (-2315 3010);
PAINT MONO (-2315 3010);
FORCEPROP 2 LASTPIN (-2325 2150) $PN 1
J 0
(-2315 2160);
DISPLAY 0.617021 (-2315 2160);
PAINT MONO (-2315 2160);
FORCEPROP 1 LAST NEEDS_NO_SIZE TRUE
J 0
(-2725 2400);
DISPLAY 0.723404 (-2725 2400);
PAINT GREEN (-2725 2400);
DISPLAY INVISIBLE (-2725 2400);
FORCEPROP 1 LAST CDS_LMAN_SYM_OUTLINE -300,700,250,-650
J 0
(-2725 2400);
DISPLAY 0.468085 (-2725 2400);
PAINT GREEN (-2725 2400);
DISPLAY INVISIBLE (-2725 2400);
FORCEPROP 2 LAST CDS_LIB pure_quanta
J 0
(-2725 2400);
DISPLAY INVISIBLE (-2725 2400);
FORCEPROP 1 LAST PATH I16
J 0
(-2725 2400);
DISPLAY 0.723404 (-2725 2400);
PAINT GREEN (-2725 2400);
DISPLAY INVISIBLE (-2725 2400);
FORCEPROP 2 LAST $SEC 1
J 0
(-3025 3325);
DISPLAY 0.680851 (-3025 3325);
PAINT MONO (-3025 3325);
DISPLAY INVISIBLE (-3025 3325);
FORCEPROP 2 LAST CDS_SEC 1
J 0
(-2975 3400);
DISPLAY 1.021277 (-2975 3400);
DISPLAY INVISIBLE (-2975 3400);
FORCEADD UNIVERSAL_GND..1
(-4250 2600);
FORCEPROP 3 LASTPIN (-4250 2650) SIG_NAME GND\g
J 0
(-4240 2660);
DISPLAY 0.659574 (-4240 2660);
PAINT MONO (-4240 2660);
DISPLAY INVISIBLE (-4240 2660);
FORCEPROP 1 LAST HDL_POWER GND
J 1
(-4225 2525);
DISPLAY 0.872340 (-4225 2525);
PAINT GREEN (-4225 2525);
DISPLAY INVISIBLE (-4225 2525);
FORCEPROP 2 LAST CDS_LIB logical_power
J 0
(-4250 2600);
PAINT MONO (-4250 2600);
DISPLAY INVISIBLE (-4250 2600);
FORCEPROP 1 LAST PATH I17
J 0
(-4175 2600);
DISPLAY 0.872340 (-4175 2600);
PAINT AQUA (-4175 2600);
DISPLAY INVISIBLE (-4175 2600);
FORCEADD Q_CAP..1
(-4250 2850);
FORCEPROP 1 LAST PART_NUMBER CH5222KEB01
J 0
(-4200 2675);
DISPLAY 0.617021 (-4200 2675);
PAINT BLUE (-4200 2675);
DISPLAY INVISIBLE (-4200 2675);
FORCEPROP 1 LAST PACK_TYPE C0402
J 0
(-4200 2725);
DISPLAY 0.617021 (-4200 2725);
PAINT SKYBLUE (-4200 2725);
FORCEPROP 1 LAST VOLTAGE 10V
J 0
(-4200 2875);
DISPLAY 0.617021 (-4200 2875);
PAINT SKYBLUE (-4200 2875);
FORCEPROP 1 LAST VALUE 2.2UF
J 0
(-4200 2925);
DISPLAY 0.617021 (-4200 2925);
PAINT SKYBLUE (-4200 2925);
FORCEPROP 1 LAST TOLERANCE 10%
J 0
(-4200 2825);
DISPLAY 0.617021 (-4200 2825);
PAINT SKYBLUE (-4200 2825);
FORCEPROP 1 LAST MATERIAL X6S
J 0
(-4200 2775);
DISPLAY 0.617021 (-4200 2775);
PAINT SKYBLUE (-4200 2775);
FORCEPROP 1 LAST LOCATION PC601
J 0
(-4200 2975);
DISPLAY 0.617021 (-4200 2975);
PAINT AQUA (-4200 2975);
FORCEPROP 1 LASTPIN (-4250 2950) $PN 1
J 0
(-4240 2930);
DISPLAY 0.617021 (-4240 2930);
PAINT MONO (-4240 2930);
FORCEPROP 1 LASTPIN (-4250 2750) $PN 2
J 0
(-4240 2730);
DISPLAY 0.617021 (-4240 2730);
PAINT MONO (-4240 2730);
FORCEPROP 2 LAST CDS_LIB pure_quanta
J 0
(-4250 2850);
DISPLAY INVISIBLE (-4250 2850);
FORCEPROP 1 LAST PATH I18
J 0
(-4200 3000);
DISPLAY 0.978723 (-4200 3000);
PAINT WHITE (-4200 3000);
DISPLAY INVISIBLE (-4200 3000);
FORCEPROP 1 LAST LOCATION PC601
J 0
(-4200 3025);
DISPLAY 1.021277 (-4200 3025);
PAINT AQUA (-4200 3025);
DISPLAY INVISIBLE (-4200 3025);
FORCEPROP 0 LAST $SEC 1
J 0
(-4200 3025);
DISPLAY 0.680851 (-4200 3025);
PAINT MONO (-4200 3025);
DISPLAY INVISIBLE (-4200 3025);
FORCEPROP 0 LAST CDS_SEC 1
J 0
(-4200 3025);
DISPLAY 1.021277 (-4200 3025);
DISPLAY INVISIBLE (-4200 3025);
FORCEADD Q_RES..2
(-4250 3250);
FORCEPROP 1 LAST PART_NUMBER CS-2202FB01
J 0
(-4210 3125);
DISPLAY 0.617021 (-4210 3125);
PAINT BLUE (-4210 3125);
DISPLAY INVISIBLE (-4210 3125);
FORCEPROP 1 LAST VALUE 2.2
J 0
(-4205 3325);
DISPLAY 0.617021 (-4205 3325);
PAINT SKYBLUE (-4205 3325);
FORCEPROP 1 LAST WATTAGE 1/16W
J 0
(-4210 3225);
DISPLAY 0.617021 (-4210 3225);
PAINT SKYBLUE (-4210 3225);
FORCEPROP 1 LAST TOLERANCE 1%
J 0
(-4205 3275);
DISPLAY 0.617021 (-4205 3275);
PAINT SKYBLUE (-4205 3275);
FORCEPROP 1 LAST MATERIAL CHIP
J 0
(-4210 3175);
DISPLAY 0.617021 (-4210 3175);
PAINT SKYBLUE (-4210 3175);
FORCEPROP 1 LAST PACK_TYPE 0402LF
J 0
(-4210 3075);
DISPLAY 0.617021 (-4210 3075);
PAINT SKYBLUE (-4210 3075);
FORCEPROP 1 LAST LOCATION PR356
J 0
(-4205 3375);
DISPLAY 0.617021 (-4205 3375);
PAINT AQUA (-4205 3375);
FORCEPROP 1 LASTPIN (-4250 3350) $PN 1
J 0
(-4245 3312);
DISPLAY 0.617021 (-4245 3312);
PAINT MONO (-4245 3312);
FORCEPROP 1 LASTPIN (-4250 3150) $PN 2
J 0
(-4245 3160);
DISPLAY 0.617021 (-4245 3160);
PAINT MONO (-4245 3160);
FORCEPROP 2 LAST CDS_LIB pure_quanta
J 0
(-4250 3250);
DISPLAY INVISIBLE (-4250 3250);
FORCEPROP 1 LAST PATH I19
J 0
(-4200 3425);
DISPLAY 0.978723 (-4200 3425);
PAINT WHITE (-4200 3425);
DISPLAY INVISIBLE (-4200 3425);
FORCEPROP 1 LAST LOCATION PR356
J 0
(-4200 3425);
DISPLAY 1.021277 (-4200 3425);
PAINT AQUA (-4200 3425);
DISPLAY INVISIBLE (-4200 3425);
FORCEPROP 0 LAST $SEC 1
J 0
(-4200 3425);
DISPLAY 0.680851 (-4200 3425);
PAINT MONO (-4200 3425);
DISPLAY INVISIBLE (-4200 3425);
FORCEPROP 0 LAST CDS_SEC 1
J 0
(-4200 3425);
DISPLAY 1.021277 (-4200 3425);
DISPLAY INVISIBLE (-4200 3425);
FORCEADD Q_RES..2
R 2
(-4750 1900);
FORCEPROP 1 LAST PART_NUMBER CS28872FB01
J 2
(-4800 1775);
DISPLAY 0.617021 (-4800 1775);
PAINT BLUE (-4800 1775);
DISPLAY INVISIBLE (-4800 1775);
FORCEPROP 1 LAST PACK_TYPE 0402LF
J 2
(-4800 1725);
DISPLAY 0.617021 (-4800 1725);
PAINT SKYBLUE (-4800 1725);
FORCEPROP 1 LAST MATERIAL EMPTY
J 2
(-4800 1825);
DISPLAY 0.617021 (-4800 1825);
PAINT RED (-4800 1825);
FORCEPROP 1 LAST WATTAGE 1/16W
J 2
(-4800 1875);
DISPLAY 0.617021 (-4800 1875);
PAINT SKYBLUE (-4800 1875);
FORCEPROP 1 LAST VALUE 8.87K
J 2
(-4805 1975);
DISPLAY 0.617021 (-4805 1975);
PAINT SKYBLUE (-4805 1975);
FORCEPROP 1 LAST TOLERANCE 1%
J 2
(-4805 1925);
DISPLAY 0.617021 (-4805 1925);
PAINT SKYBLUE (-4805 1925);
FORCEPROP 1 LAST LOCATION PR353
J 2
(-4795 2025);
DISPLAY 0.617021 (-4795 2025);
PAINT AQUA (-4795 2025);
FORCEPROP 1 LASTPIN (-4750 2000) $PN 1
J 2
(-4755 1962);
DISPLAY 0.617021 (-4755 1962);
PAINT MONO (-4755 1962);
FORCEPROP 1 LASTPIN (-4750 1800) $PN 2
J 2
(-4755 1810);
DISPLAY 0.617021 (-4755 1810);
PAINT MONO (-4755 1810);
FORCEPROP 2 LAST CDS_LIB pure_quanta
J 2
(-4750 1900);
DISPLAY INVISIBLE (-4750 1900);
FORCEPROP 1 LAST PATH I2
J 2
(-4800 2075);
DISPLAY 0.978723 (-4800 2075);
PAINT WHITE (-4800 2075);
DISPLAY INVISIBLE (-4800 2075);
FORCEPROP 1 LAST LOCATION PR353
J 2
(-4800 2075);
DISPLAY 1.021277 (-4800 2075);
PAINT AQUA (-4800 2075);
DISPLAY INVISIBLE (-4800 2075);
FORCEPROP 0 LAST $SEC 1
J 2
(-4800 2075);
DISPLAY 0.680851 (-4800 2075);
PAINT MONO (-4800 2075);
DISPLAY INVISIBLE (-4800 2075);
FORCEPROP 0 LAST CDS_SEC 1
J 2
(-4800 2075);
DISPLAY 1.021277 (-4800 2075);
DISPLAY INVISIBLE (-4800 2075);
FORCEADD UNIVERSAL_GND..1
(-3725 3000);
FORCEPROP 3 LASTPIN (-3725 3050) SIG_NAME GND\g
J 0
(-3715 3060);
DISPLAY 0.659574 (-3715 3060);
PAINT MONO (-3715 3060);
DISPLAY INVISIBLE (-3715 3060);
FORCEPROP 1 LAST HDL_POWER GND
J 1
(-3700 2925);
DISPLAY 0.872340 (-3700 2925);
PAINT GREEN (-3700 2925);
DISPLAY INVISIBLE (-3700 2925);
FORCEPROP 2 LAST CDS_LIB logical_power
J 0
(-3725 3000);
PAINT MONO (-3725 3000);
DISPLAY INVISIBLE (-3725 3000);
FORCEPROP 1 LAST PATH I20
J 0
(-3650 3000);
DISPLAY 0.872340 (-3650 3000);
PAINT AQUA (-3650 3000);
DISPLAY INVISIBLE (-3650 3000);
FORCEADD Q_CAP..1
(-3725 3250);
FORCEPROP 1 LAST PART_NUMBER CH5222KEB01
J 0
(-3675 3100);
DISPLAY 0.617021 (-3675 3100);
PAINT BLUE (-3675 3100);
DISPLAY INVISIBLE (-3675 3100);
FORCEPROP 1 LAST VALUE 2.2UF
J 0
(-3675 3300);
DISPLAY 0.617021 (-3675 3300);
PAINT SKYBLUE (-3675 3300);
FORCEPROP 1 LAST VOLTAGE 10V
J 0
(-3675 3250);
DISPLAY 0.617021 (-3675 3250);
PAINT SKYBLUE (-3675 3250);
FORCEPROP 1 LAST TOLERANCE 10%
J 0
(-3675 3200);
DISPLAY 0.617021 (-3675 3200);
PAINT SKYBLUE (-3675 3200);
FORCEPROP 1 LAST MATERIAL X6S
J 0
(-3675 3150);
DISPLAY 0.617021 (-3675 3150);
PAINT SKYBLUE (-3675 3150);
FORCEPROP 1 LAST PACK_TYPE C0402
J 0
(-3675 3050);
DISPLAY 0.617021 (-3675 3050);
PAINT SKYBLUE (-3675 3050);
FORCEPROP 1 LAST LOCATION PC1212_P0_2
J 0
(-3675 3350);
DISPLAY 0.617021 (-3675 3350);
PAINT AQUA (-3675 3350);
FORCEPROP 1 LASTPIN (-3725 3350) $PN 1
J 0
(-3715 3330);
DISPLAY 0.617021 (-3715 3330);
FORCEPROP 1 LASTPIN (-3725 3150) $PN 2
J 0
(-3715 3130);
DISPLAY 0.617021 (-3715 3130);
FORCEPROP 2 LAST CDS_LIB pure_quanta
J 0
(-3725 3250);
PAINT MONO (-3725 3250);
DISPLAY INVISIBLE (-3725 3250);
FORCEPROP 1 LAST PATH I21
J 0
(-3675 3400);
DISPLAY 0.978723 (-3675 3400);
PAINT WHITE (-3675 3400);
DISPLAY INVISIBLE (-3675 3400);
FORCEPROP 2 LAST $SEC 1
J 0
(-3675 3450);
DISPLAY 0.680851 (-3675 3450);
PAINT MONO (-3675 3450);
DISPLAY INVISIBLE (-3675 3450);
FORCEPROP 2 LAST CDS_SEC 1
J 0
(-3675 3450);
DISPLAY 1.021277 (-3675 3450);
DISPLAY INVISIBLE (-3675 3450);
FORCEADD Q_RES..2
(-4175 3900);
FORCEPROP 1 LAST PART_NUMBER CS00002JB13
J 0
(-4135 3775);
DISPLAY 0.617021 (-4135 3775);
PAINT BLUE (-4135 3775);
DISPLAY INVISIBLE (-4135 3775);
FORCEPROP 1 LAST VALUE 0
J 0
(-4130 3975);
DISPLAY 0.617021 (-4130 3975);
PAINT SKYBLUE (-4130 3975);
FORCEPROP 1 LAST WATTAGE 1/16W
J 0
(-4135 3875);
DISPLAY 0.617021 (-4135 3875);
PAINT SKYBLUE (-4135 3875);
FORCEPROP 1 LAST PACK_TYPE 0402LF
J 0
(-4135 3725);
DISPLAY 0.617021 (-4135 3725);
PAINT SKYBLUE (-4135 3725);
FORCEPROP 1 LAST TOLERANCE 5%
J 0
(-4130 3925);
DISPLAY 0.617021 (-4130 3925);
PAINT SKYBLUE (-4130 3925);
FORCEPROP 1 LAST MATERIAL EMPTY
J 0
(-4135 3825);
DISPLAY 0.617021 (-4135 3825);
PAINT RED (-4135 3825);
FORCEPROP 1 LAST LOCATION PR633
J 0
(-4130 4025);
DISPLAY 0.617021 (-4130 4025);
PAINT AQUA (-4130 4025);
FORCEPROP 2 LAST CDS_LIB pure_quanta
J 0
(-4175 3900);
DISPLAY INVISIBLE (-4175 3900);
FORCEPROP 1 LAST PATH I22
J 0
(-4125 4075);
DISPLAY 0.978723 (-4125 4075);
PAINT WHITE (-4125 4075);
DISPLAY INVISIBLE (-4125 4075);
FORCEPROP 0 LAST $SEC 1
J 0
(-4125 4075);
DISPLAY INVISIBLE (-4125 4075);
FORCEPROP 0 LAST CDS_SEC 1
J 0
(-4125 4075);
DISPLAY INVISIBLE (-4125 4075);
FORCEPROP 1 LASTPIN (-4175 4000) $PN 1
J 0
(-4170 3962);
DISPLAY 0.787234 (-4170 3962);
PAINT MONO (-4170 3962);
DISPLAY INVISIBLE (-4170 3962);
FORCEPROP 1 LASTPIN (-4175 3800) $PN 2
J 0
(-4170 3810);
DISPLAY 0.787234 (-4170 3810);
PAINT MONO (-4170 3810);
DISPLAY INVISIBLE (-4170 3810);
FORCEADD VCC15..1
(-4175 4125);
FORCEPROP 3 LASTPIN (-4175 4075) SIG_NAME P3V3\g
J 0
(-4165 4085);
DISPLAY 0.659574 (-4165 4085);
PAINT MONO (-4165 4085);
DISPLAY INVISIBLE (-4165 4085);
FORCEPROP 1 LAST HDL_POWER P3V3
J 1
(-4175 4175);
DISPLAY 0.617021 (-4175 4175);
PAINT GREEN (-4175 4175);
FORCEPROP 2 LAST CDS_LIB logical_power
J 0
(-4175 4125);
DISPLAY INVISIBLE (-4175 4125);
FORCEPROP 1 LAST PATH I23
J 0
(-4125 4150);
DISPLAY 0.872340 (-4125 4150);
PAINT AQUA (-4125 4150);
DISPLAY INVISIBLE (-4125 4150);
FORCEADD OFFPAGE..1
(-4250 4600);
FORCEPROP 2 LAST $XR0 266 
J 0
(-4502 4600);
DISPLAY 0.638298 (-4502 4600);
PAINT MONO (-4502 4600);
FORCEPROP 1 LAST COMMENT_BODY TRUE
J 0
(-4125 4500);
DISPLAY 0.872340 (-4125 4500);
PAINT GREEN (-4125 4500);
DISPLAY INVISIBLE (-4125 4500);
FORCEPROP 1 LAST OFFPAGE TRUE
J 0
(-3925 4475);
DISPLAY 0.872340 (-3925 4475);
PAINT GREEN (-3925 4475);
DISPLAY INVISIBLE (-3925 4475);
FORCEPROP 2 LAST CDS_LIB standard
J 0
(-4250 4600);
DISPLAY INVISIBLE (-4250 4600);
FORCEPROP 2 LAST PATH I24
J 0
(-4500 4650);
DISPLAY 1.021277 (-4500 4650);
DISPLAY INVISIBLE (-4500 4650);
FORCEADD ISL99390FRZTR5935..1
(-2725 5200);
FORCEPROP 1 LAST PART_NUMBER AL099390004
J 0
(-3025 6000);
DISPLAY 0.617021 (-3025 6000);
PAINT BLUE (-3025 6000);
DISPLAY INVISIBLE (-3025 6000);
FORCEPROP 2 LAST VALUE ISL99390FRZ-TR5935
J 0
(-3025 6175);
DISPLAY 0.617021 (-3025 6175);
PAINT SKYBLUE (-3025 6175);
FORCEPROP 1 LAST MATERIAL IC
J 0
(-3025 5925);
DISPLAY 0.617021 (-3025 5925);
PAINT SKYBLUE (-3025 5925);
FORCEPROP 2 LAST PART_TYPE SMLF
J 0
(-3025 6225);
DISPLAY 0.638298 (-3025 6225);
FORCEPROP 1 LAST LOCATION PU69_P0_1
J 0
(-3025 6075);
DISPLAY 0.617021 (-3025 6075);
PAINT AQUA (-3025 6075);
FORCEPROP 2 LASTPIN (-2325 4750) $PN 2
J 0
(-2315 4760);
DISPLAY 0.617021 (-2315 4760);
PAINT MONO (-2315 4760);
FORCEPROP 2 LASTPIN (-2325 5550) $PN 33
J 0
(-2315 5560);
DISPLAY 0.617021 (-2315 5560);
PAINT MONO (-2315 5560);
FORCEPROP 2 LASTPIN (-3175 4950) $PN 31
J 2
(-3185 4960);
DISPLAY 0.617021 (-3185 4960);
PAINT MONO (-3185 4960);
FORCEPROP 2 LASTPIN (-3175 5350) $PN 35
J 2
(-3185 5360);
DISPLAY 0.617021 (-3185 5360);
PAINT MONO (-3185 5360);
FORCEPROP 2 LASTPIN (-2325 4900) $PN 6
J 0
(-2315 4910);
DISPLAY 0.617021 (-2315 4910);
PAINT MONO (-2315 4910);
FORCEPROP 2 LASTPIN (-2325 4850) $PN 41
J 0
(-2315 4860);
DISPLAY 0.617021 (-2315 4860);
PAINT MONO (-2315 4860);
FORCEPROP 2 LASTPIN (-3175 5200) $PN 38
J 2
(-3185 5210);
DISPLAY 0.617021 (-3185 5210);
PAINT MONO (-3185 5210);
FORCEPROP 2 LASTPIN (-3175 4900) $PN 37
J 2
(-3185 4910);
DISPLAY 0.617021 (-3185 4910);
PAINT MONO (-3185 4910);
FORCEPROP 2 LASTPIN (-2325 4700) $PN 5
J 0
(-2315 4710);
DISPLAY 0.617021 (-2315 4710);
PAINT MONO (-2315 4710);
FORCEPROP 2 LASTPIN (-2325 4650) $PN 7_9-20_24
J 0
(-2315 4660);
DISPLAY 0.617021 (-2315 4660);
PAINT MONO (-2315 4660);
FORCEPROP 2 LASTPIN (-2325 4600) $PN 40
J 0
(-2315 4610);
DISPLAY 0.617021 (-2315 4610);
PAINT MONO (-2315 4610);
FORCEPROP 2 LASTPIN (-2325 5300) $PN 32
J 0
(-2315 5310);
DISPLAY 0.617021 (-2315 5310);
PAINT MONO (-2315 5310);
FORCEPROP 2 LASTPIN (-3175 5850) $PN 4
J 2
(-3185 5860);
DISPLAY 0.617021 (-3185 5860);
PAINT MONO (-3185 5860);
FORCEPROP 2 LASTPIN (-3175 4600) $PN 34
J 2
(-3185 4610);
DISPLAY 0.617021 (-3185 4610);
PAINT MONO (-3185 4610);
FORCEPROP 2 LASTPIN (-3175 5100) $PN 39
J 2
(-3185 5110);
DISPLAY 0.617021 (-3185 5110);
PAINT MONO (-3185 5110);
FORCEPROP 2 LASTPIN (-2325 5200) $PN 10_19
J 0
(-2315 5210);
DISPLAY 0.617021 (-2315 5210);
PAINT MONO (-2315 5210);
FORCEPROP 2 LASTPIN (-3175 4700) $PN 36
J 2
(-3185 4710);
DISPLAY 0.617021 (-3185 4710);
PAINT MONO (-3185 4710);
FORCEPROP 2 LASTPIN (-3175 5550) $PN 3
J 2
(-3185 5560);
DISPLAY 0.617021 (-3185 5560);
PAINT MONO (-3185 5560);
FORCEPROP 2 LASTPIN (-2325 5850) $PN 25_29
J 0
(-2315 5860);
DISPLAY 0.617021 (-2315 5860);
PAINT MONO (-2315 5860);
FORCEPROP 2 LASTPIN (-2325 5800) $PN 30
J 0
(-2315 5810);
DISPLAY 0.617021 (-2315 5810);
PAINT MONO (-2315 5810);
FORCEPROP 2 LASTPIN (-2325 4950) $PN 1
J 0
(-2315 4960);
DISPLAY 0.617021 (-2315 4960);
PAINT MONO (-2315 4960);
FORCEPROP 1 LAST NEEDS_NO_SIZE TRUE
J 0
(-2725 5200);
DISPLAY 0.723404 (-2725 5200);
PAINT GREEN (-2725 5200);
DISPLAY INVISIBLE (-2725 5200);
FORCEPROP 1 LAST CDS_LMAN_SYM_OUTLINE -300,700,250,-650
J 0
(-2725 5200);
DISPLAY 0.468085 (-2725 5200);
PAINT GREEN (-2725 5200);
DISPLAY INVISIBLE (-2725 5200);
FORCEPROP 2 LAST CDS_LIB pure_quanta
J 0
(-2725 5200);
DISPLAY INVISIBLE (-2725 5200);
FORCEPROP 1 LAST PATH I25
J 0
(-2725 5200);
DISPLAY 0.723404 (-2725 5200);
PAINT GREEN (-2725 5200);
DISPLAY INVISIBLE (-2725 5200);
FORCEPROP 2 LAST $SEC 1
J 0
(-3025 6125);
DISPLAY 0.680851 (-3025 6125);
PAINT MONO (-3025 6125);
DISPLAY INVISIBLE (-3025 6125);
FORCEPROP 2 LAST CDS_SEC 1
J 0
(-2975 6200);
DISPLAY 1.021277 (-2975 6200);
DISPLAY INVISIBLE (-2975 6200);
FORCEADD UNIVERSAL_GND..1
(-2075 1675);
FORCEPROP 3 LASTPIN (-2075 1725) SIG_NAME GND\g
J 0
(-2065 1735);
DISPLAY 0.659574 (-2065 1735);
PAINT MONO (-2065 1735);
DISPLAY INVISIBLE (-2065 1735);
FORCEPROP 1 LAST HDL_POWER GND
J 1
(-2050 1600);
DISPLAY 0.872340 (-2050 1600);
PAINT GREEN (-2050 1600);
DISPLAY INVISIBLE (-2050 1600);
FORCEPROP 2 LAST CDS_LIB logical_power
J 0
(-2075 1675);
PAINT MONO (-2075 1675);
DISPLAY INVISIBLE (-2075 1675);
FORCEPROP 1 LAST PATH I26
J 0
(-2000 1675);
DISPLAY 0.872340 (-2000 1675);
PAINT AQUA (-2000 1675);
DISPLAY INVISIBLE (-2000 1675);
FORCEADD Q_CAP..1
(-1925 3300);
FORCEPROP 1 LAST PART_NUMBER TMP_QCH2336K1B12
J 0
(-1875 3150);
DISPLAY 0.617021 (-1875 3150);
PAINT BLUE (-1875 3150);
DISPLAY INVISIBLE (-1875 3150);
FORCEPROP 1 LAST MATERIAL X7R
J 0
(-1875 3250);
DISPLAY 0.617021 (-1875 3250);
PAINT SKYBLUE (-1875 3250);
FORCEPROP 1 LAST PACK_TYPE 0402
J 0
(-1875 3200);
DISPLAY 0.617021 (-1875 3200);
PAINT SKYBLUE (-1875 3200);
FORCEPROP 1 LAST VOLTAGE 50V
J 0
(-1875 3350);
DISPLAY 0.617021 (-1875 3350);
PAINT SKYBLUE (-1875 3350);
FORCEPROP 1 LAST VALUE 3300PF
J 0
(-1875 3400);
DISPLAY 0.617021 (-1875 3400);
PAINT SKYBLUE (-1875 3400);
FORCEPROP 1 LAST TOLERANCE 10%
J 0
(-1875 3300);
DISPLAY 0.617021 (-1875 3300);
PAINT SKYBLUE (-1875 3300);
FORCEPROP 1 LAST LOCATION PC603_P0_2
J 0
(-1875 3450);
DISPLAY 0.617021 (-1875 3450);
PAINT AQUA (-1875 3450);
FORCEPROP 1 LASTPIN (-1925 3400) $PN 1
J 0
(-1915 3380);
DISPLAY 0.617021 (-1915 3380);
PAINT MONO (-1915 3380);
FORCEPROP 1 LASTPIN (-1925 3200) $PN 2
J 0
(-1915 3180);
DISPLAY 0.617021 (-1915 3180);
PAINT MONO (-1915 3180);
FORCEPROP 2 LAST CDS_LIB pure_quanta
J 0
(-1925 3300);
DISPLAY INVISIBLE (-1925 3300);
FORCEPROP 1 LAST PATH I27
J 0
(-1875 3450);
DISPLAY 0.978723 (-1875 3450);
PAINT WHITE (-1875 3450);
DISPLAY INVISIBLE (-1875 3450);
FORCEPROP 1 LAST LOCATION PC603_P0_2
J 0
(-1875 3500);
DISPLAY 1.021277 (-1875 3500);
PAINT AQUA (-1875 3500);
DISPLAY INVISIBLE (-1875 3500);
FORCEPROP 0 LAST $SEC 1
J 0
(-1875 3500);
DISPLAY 0.680851 (-1875 3500);
PAINT MONO (-1875 3500);
DISPLAY INVISIBLE (-1875 3500);
FORCEPROP 0 LAST CDS_SEC 1
J 0
(-1875 3500);
DISPLAY 1.021277 (-1875 3500);
DISPLAY INVISIBLE (-1875 3500);
FORCEADD Q_CAP..1
(-1525 3300);
FORCEPROP 1 LAST PART_NUMBER CH5103KEB01
J 0
(-1475 3150);
DISPLAY 0.617021 (-1475 3150);
PAINT BLUE (-1475 3150);
DISPLAY INVISIBLE (-1475 3150);
FORCEPROP 1 LAST TOLERANCE 10%
J 0
(-1475 3300);
DISPLAY 0.617021 (-1475 3300);
PAINT SKYBLUE (-1475 3300);
FORCEPROP 1 LAST PACK_TYPE C0402
J 0
(-1475 3200);
DISPLAY 0.617021 (-1475 3200);
PAINT SKYBLUE (-1475 3200);
FORCEPROP 1 LAST VOLTAGE 16V
J 0
(-1475 3350);
DISPLAY 0.617021 (-1475 3350);
PAINT SKYBLUE (-1475 3350);
FORCEPROP 1 LAST VALUE 1UF
J 0
(-1475 3400);
DISPLAY 0.617021 (-1475 3400);
PAINT SKYBLUE (-1475 3400);
FORCEPROP 1 LAST MATERIAL X6S
J 0
(-1475 3250);
DISPLAY 0.617021 (-1475 3250);
PAINT SKYBLUE (-1475 3250);
FORCEPROP 1 LAST LOCATION PC605_P0_2
J 0
(-1475 3450);
DISPLAY 0.617021 (-1475 3450);
PAINT AQUA (-1475 3450);
FORCEPROP 1 LASTPIN (-1525 3400) $PN 1
J 0
(-1515 3380);
DISPLAY 0.617021 (-1515 3380);
PAINT MONO (-1515 3380);
FORCEPROP 1 LASTPIN (-1525 3200) $PN 2
J 0
(-1515 3180);
DISPLAY 0.617021 (-1515 3180);
PAINT MONO (-1515 3180);
FORCEPROP 2 LAST CDS_LIB pure_quanta
J 0
(-1525 3300);
DISPLAY INVISIBLE (-1525 3300);
FORCEPROP 1 LAST PATH I28
J 0
(-1475 3450);
DISPLAY 0.978723 (-1475 3450);
PAINT WHITE (-1475 3450);
DISPLAY INVISIBLE (-1475 3450);
FORCEPROP 1 LAST LOCATION PC605_P0_2
J 0
(-1475 3500);
DISPLAY 1.021277 (-1475 3500);
PAINT AQUA (-1475 3500);
DISPLAY INVISIBLE (-1475 3500);
FORCEPROP 0 LAST $SEC 1
J 0
(-1475 3500);
DISPLAY 0.680851 (-1475 3500);
PAINT MONO (-1475 3500);
DISPLAY INVISIBLE (-1475 3500);
FORCEPROP 0 LAST CDS_SEC 1
J 0
(-1475 3500);
DISPLAY 1.021277 (-1475 3500);
DISPLAY INVISIBLE (-1475 3500);
FORCEADD UNIVERSAL_GND..1
(-2075 4475);
FORCEPROP 3 LASTPIN (-2075 4525) SIG_NAME GND\g
J 0
(-2065 4535);
DISPLAY 0.659574 (-2065 4535);
PAINT MONO (-2065 4535);
DISPLAY INVISIBLE (-2065 4535);
FORCEPROP 1 LAST HDL_POWER GND
J 1
(-2050 4400);
DISPLAY 0.872340 (-2050 4400);
PAINT GREEN (-2050 4400);
DISPLAY INVISIBLE (-2050 4400);
FORCEPROP 2 LAST CDS_LIB logical_power
J 0
(-2075 4475);
PAINT MONO (-2075 4475);
DISPLAY INVISIBLE (-2075 4475);
FORCEPROP 1 LAST PATH I29
J 0
(-2000 4475);
DISPLAY 0.872340 (-2000 4475);
PAINT AQUA (-2000 4475);
DISPLAY INVISIBLE (-2000 4475);
FORCEADD UNIVERSAL_GND..1
(-4800 2125);
FORCEPROP 3 LASTPIN (-4800 2175) SIG_NAME GND\g
J 0
(-4790 2185);
DISPLAY 0.659574 (-4790 2185);
PAINT MONO (-4790 2185);
DISPLAY INVISIBLE (-4790 2185);
FORCEPROP 1 LAST HDL_POWER GND
J 1
(-4775 2050);
DISPLAY 0.872340 (-4775 2050);
PAINT GREEN (-4775 2050);
DISPLAY INVISIBLE (-4775 2050);
FORCEPROP 2 LAST CDS_LIB logical_power
J 0
(-4800 2125);
PAINT MONO (-4800 2125);
DISPLAY INVISIBLE (-4800 2125);
FORCEPROP 1 LAST PATH I3
J 0
(-4725 2125);
DISPLAY 0.872340 (-4725 2125);
PAINT AQUA (-4725 2125);
DISPLAY INVISIBLE (-4725 2125);
FORCEADD Q_RES..1
(-1225 2850);
FORCEPROP 1 LAST PART_NUMBER CS-3302FB01
J 0
(-1325 2900);
DISPLAY 0.617021 (-1325 2900);
PAINT BLUE (-1325 2900);
DISPLAY INVISIBLE (-1325 2900);
FORCEPROP 1 LAST VALUE 3.3
J 2
(-1000 2850);
DISPLAY 0.617021 (-1000 2850);
PAINT SKYBLUE (-1000 2850);
FORCEPROP 1 LAST WATTAGE 1/16W
J 2
(-950 2925);
DISPLAY 0.617021 (-950 2925);
PAINT SKYBLUE (-950 2925);
FORCEPROP 1 LAST PACK_TYPE 0402LF
J 0
(-1325 2925);
DISPLAY 0.617021 (-1325 2925);
PAINT SKYBLUE (-1325 2925);
FORCEPROP 1 LAST MATERIAL CHIP
J 0
(-1325 2950);
DISPLAY 0.617021 (-1325 2950);
PAINT SKYBLUE (-1325 2950);
FORCEPROP 1 LAST TOLERANCE 1%
J 0
(-975 2850);
DISPLAY 0.617021 (-975 2850);
PAINT SKYBLUE (-975 2850);
FORCEPROP 1 LAST LOCATION PR1781
J 0
(-1475 2850);
DISPLAY 0.617021 (-1475 2850);
PAINT AQUA (-1475 2850);
FORCEPROP 1 LASTPIN (-1325 2850) $PN 1
J 0
(-1313 2862);
DISPLAY 0.617021 (-1313 2862);
FORCEPROP 1 LASTPIN (-1125 2850) $PN 2
J 0
(-1163 2862);
DISPLAY 0.617021 (-1163 2862);
FORCEPROP 2 LAST CDS_LIB pure_quanta
J 0
(-1225 2850);
PAINT MONO (-1225 2850);
DISPLAY INVISIBLE (-1225 2850);
FORCEPROP 1 LAST PATH I30
J 0
(-1275 3000);
DISPLAY 0.978723 (-1275 3000);
PAINT WHITE (-1275 3000);
DISPLAY INVISIBLE (-1275 3000);
FORCEPROP 2 LAST $SEC 1
J 0
(-1275 3050);
DISPLAY 0.680851 (-1275 3050);
PAINT MONO (-1275 3050);
DISPLAY INVISIBLE (-1275 3050);
FORCEPROP 2 LAST CDS_SEC 1
J 0
(-1275 3050);
DISPLAY 1.021277 (-1275 3050);
DISPLAY INVISIBLE (-1275 3050);
FORCEADD Q_CAP..1
(-1125 3300);
FORCEPROP 1 LAST PART_NUMBER CH6223MEA01
J 0
(-1075 3150);
DISPLAY 0.617021 (-1075 3150);
PAINT BLUE (-1075 3150);
DISPLAY INVISIBLE (-1075 3150);
FORCEPROP 1 LAST TOLERANCE 20%
J 0
(-1075 3300);
DISPLAY 0.617021 (-1075 3300);
PAINT SKYBLUE (-1075 3300);
FORCEPROP 1 LAST VALUE 22UF
J 0
(-1075 3400);
DISPLAY 0.617021 (-1075 3400);
PAINT SKYBLUE (-1075 3400);
FORCEPROP 1 LAST PACK_TYPE C0805
J 0
(-1075 3200);
DISPLAY 0.617021 (-1075 3200);
PAINT SKYBLUE (-1075 3200);
FORCEPROP 1 LAST VOLTAGE 16V
J 0
(-1075 3350);
DISPLAY 0.617021 (-1075 3350);
PAINT SKYBLUE (-1075 3350);
FORCEPROP 1 LAST MATERIAL X6S
J 0
(-1075 3250);
DISPLAY 0.617021 (-1075 3250);
PAINT SKYBLUE (-1075 3250);
FORCEPROP 1 LAST LOCATION PC609_P0_2
J 0
(-1075 3450);
DISPLAY 0.617021 (-1075 3450);
PAINT AQUA (-1075 3450);
FORCEPROP 1 LASTPIN (-1125 3400) $PN 1
J 0
(-1115 3380);
DISPLAY 0.617021 (-1115 3380);
PAINT MONO (-1115 3380);
FORCEPROP 1 LASTPIN (-1125 3200) $PN 2
J 0
(-1115 3180);
DISPLAY 0.617021 (-1115 3180);
PAINT MONO (-1115 3180);
FORCEPROP 2 LAST CDS_LIB pure_quanta
J 0
(-1125 3300);
DISPLAY INVISIBLE (-1125 3300);
FORCEPROP 1 LAST PATH I31
J 0
(-1075 3450);
DISPLAY 0.978723 (-1075 3450);
PAINT WHITE (-1075 3450);
DISPLAY INVISIBLE (-1075 3450);
FORCEPROP 1 LAST LOCATION PC609_P0_2
J 0
(-1075 3500);
DISPLAY 1.021277 (-1075 3500);
PAINT AQUA (-1075 3500);
DISPLAY INVISIBLE (-1075 3500);
FORCEPROP 0 LAST $SEC 1
J 0
(-1075 3500);
DISPLAY 0.680851 (-1075 3500);
PAINT MONO (-1075 3500);
DISPLAY INVISIBLE (-1075 3500);
FORCEPROP 0 LAST CDS_SEC 1
J 0
(-1075 3500);
DISPLAY 1.021277 (-1075 3500);
DISPLAY INVISIBLE (-1075 3500);
FORCEADD Q_CAP..1
(-725 3300);
FORCEPROP 1 LAST PART_NUMBER CH6223MEA01
J 0
(-675 3150);
DISPLAY 0.617021 (-675 3150);
PAINT BLUE (-675 3150);
DISPLAY INVISIBLE (-675 3150);
FORCEPROP 1 LAST TOLERANCE 20%
J 0
(-675 3300);
DISPLAY 0.617021 (-675 3300);
PAINT SKYBLUE (-675 3300);
FORCEPROP 1 LAST VALUE 22UF
J 0
(-675 3400);
DISPLAY 0.617021 (-675 3400);
PAINT SKYBLUE (-675 3400);
FORCEPROP 1 LAST PACK_TYPE C0805
J 0
(-675 3200);
DISPLAY 0.617021 (-675 3200);
PAINT SKYBLUE (-675 3200);
FORCEPROP 1 LAST MATERIAL X6S
J 0
(-675 3250);
DISPLAY 0.617021 (-675 3250);
PAINT SKYBLUE (-675 3250);
FORCEPROP 1 LAST VOLTAGE 16V
J 0
(-675 3350);
DISPLAY 0.617021 (-675 3350);
PAINT SKYBLUE (-675 3350);
FORCEPROP 1 LAST LOCATION PC611_P0_2
J 0
(-675 3450);
DISPLAY 0.617021 (-675 3450);
PAINT AQUA (-675 3450);
FORCEPROP 1 LASTPIN (-725 3400) $PN 1
J 0
(-715 3380);
DISPLAY 0.617021 (-715 3380);
PAINT MONO (-715 3380);
FORCEPROP 1 LASTPIN (-725 3200) $PN 2
J 0
(-715 3180);
DISPLAY 0.617021 (-715 3180);
PAINT MONO (-715 3180);
FORCEPROP 2 LAST CDS_LIB pure_quanta
J 0
(-725 3300);
DISPLAY INVISIBLE (-725 3300);
FORCEPROP 1 LAST PATH I32
J 0
(-675 3450);
DISPLAY 0.978723 (-675 3450);
PAINT WHITE (-675 3450);
DISPLAY INVISIBLE (-675 3450);
FORCEPROP 1 LAST LOCATION PC611_P0_2
J 0
(-675 3500);
DISPLAY 1.021277 (-675 3500);
PAINT AQUA (-675 3500);
DISPLAY INVISIBLE (-675 3500);
FORCEPROP 0 LAST $SEC 1
J 0
(-675 3500);
DISPLAY 0.680851 (-675 3500);
PAINT MONO (-675 3500);
DISPLAY INVISIBLE (-675 3500);
FORCEPROP 0 LAST CDS_SEC 1
J 0
(-675 3500);
DISPLAY 1.021277 (-675 3500);
DISPLAY INVISIBLE (-675 3500);
FORCEADD OFFPAGE..5
(-4250 4700);
FORCEPROP 2 LAST $XR2 266 
J 0
(-4535 4736);
DISPLAY 0.638298 (-4535 4736);
PAINT MONO (-4535 4736);
FORCEPROP 2 LAST $XR1 272 
J 0
(-4535 4664);
DISPLAY 0.638298 (-4535 4664);
PAINT MONO (-4535 4664);
FORCEPROP 2 LAST $XR0 271 
J 0
(-4535 4700);
DISPLAY 0.638298 (-4535 4700);
PAINT MONO (-4535 4700);
FORCEPROP 1 LAST COMMENT_BODY TRUE
J 0
(-4150 4625);
DISPLAY 0.872340 (-4150 4625);
PAINT GREEN (-4150 4625);
DISPLAY INVISIBLE (-4150 4625);
FORCEPROP 1 LAST OFFPAGE TRUE
J 0
(-3925 4575);
DISPLAY 0.872340 (-3925 4575);
PAINT GREEN (-3925 4575);
DISPLAY INVISIBLE (-3925 4575);
FORCEPROP 2 LAST CDS_LIB standard
J 0
(-4250 4700);
DISPLAY INVISIBLE (-4250 4700);
FORCEPROP 2 LAST PATH I33
J 0
(-4525 4775);
DISPLAY 1.021277 (-4525 4775);
DISPLAY INVISIBLE (-4525 4775);
FORCEADD OFFPAGE..1
(-4250 5100);
FORCEPROP 2 LAST $XR6 272 
J 0
(-5222 5100);
DISPLAY 0.638298 (-5222 5100);
PAINT MONO (-5222 5100);
FORCEPROP 2 LAST $XR5 271 
J 0
(-5102 5100);
DISPLAY 0.638298 (-5102 5100);
PAINT MONO (-5102 5100);
FORCEPROP 2 LAST $XR4 270 
J 0
(-4982 5100);
DISPLAY 0.638298 (-4982 5100);
PAINT MONO (-4982 5100);
FORCEPROP 2 LAST $XR3 269 
J 0
(-4862 5100);
DISPLAY 0.638298 (-4862 5100);
PAINT MONO (-4862 5100);
FORCEPROP 2 LAST $XR2 268 
J 0
(-4742 5100);
DISPLAY 0.638298 (-4742 5100);
PAINT MONO (-4742 5100);
FORCEPROP 2 LAST $XR1 267 
J 0
(-4622 5100);
DISPLAY 0.638298 (-4622 5100);
PAINT MONO (-4622 5100);
FORCEPROP 2 LAST $XR0 266 
J 0
(-4502 5100);
DISPLAY 0.638298 (-4502 5100);
PAINT MONO (-4502 5100);
FORCEPROP 1 LAST COMMENT_BODY TRUE
J 0
(-4125 5000);
DISPLAY 0.872340 (-4125 5000);
PAINT GREEN (-4125 5000);
DISPLAY INVISIBLE (-4125 5000);
FORCEPROP 1 LAST OFFPAGE TRUE
J 0
(-3925 4975);
DISPLAY 0.872340 (-3925 4975);
PAINT GREEN (-3925 4975);
DISPLAY INVISIBLE (-3925 4975);
FORCEPROP 2 LAST CDS_LIB standard
J 0
(-4250 5100);
DISPLAY INVISIBLE (-4250 5100);
FORCEPROP 2 LAST PATH I34
J 0
(-4500 5150);
DISPLAY 1.021277 (-4500 5150);
DISPLAY INVISIBLE (-4500 5150);
FORCEADD Q_CAP..2
(-3975 5000);
FORCEPROP 1 LAST PART_NUMBER CH4104K1B00
J 1
(-3675 5050);
DISPLAY 0.617021 (-3675 5050);
PAINT BLUE (-3675 5050);
DISPLAY INVISIBLE (-3675 5050);
FORCEPROP 1 LAST VALUE 0.1UF
J 2
(-3675 5000);
DISPLAY 0.617021 (-3675 5000);
PAINT SKYBLUE (-3675 5000);
FORCEPROP 1 LAST VOLTAGE 25V
J 0
(-3650 5000);
DISPLAY 0.617021 (-3650 5000);
PAINT SKYBLUE (-3650 5000);
FORCEPROP 1 LAST TOLERANCE 10%
J 2
(-3325 5025);
DISPLAY 0.617021 (-3325 5025);
PAINT SKYBLUE (-3325 5025);
FORCEPROP 1 LAST MATERIAL X7R
J 0
(-3500 5050);
DISPLAY 0.617021 (-3500 5050);
PAINT SKYBLUE (-3500 5050);
FORCEPROP 1 LAST PACK_TYPE 0402
J 1
(-3475 5000);
DISPLAY 0.617021 (-3475 5000);
PAINT SKYBLUE (-3475 5000);
FORCEPROP 1 LAST LOCATION PC1349
J 1
(-4175 5000);
DISPLAY 0.617021 (-4175 5000);
PAINT AQUA (-4175 5000);
FORCEPROP 1 LASTPIN (-4075 5000) $PN 1
J 0
(-4085 5015);
DISPLAY 0.617021 (-4085 5015);
FORCEPROP 1 LASTPIN (-3875 5000) $PN 2
J 0
(-3890 5015);
DISPLAY 0.617021 (-3890 5015);
FORCEPROP 2 LAST CDS_LIB pure_quanta
J 0
(-3975 5000);
PAINT MONO (-3975 5000);
DISPLAY INVISIBLE (-3975 5000);
FORCEPROP 1 LAST PATH I35
J 0
(-3975 5200);
DISPLAY 0.978723 (-3975 5200);
PAINT WHITE (-3975 5200);
DISPLAY INVISIBLE (-3975 5200);
FORCEPROP 2 LAST $SEC 1
J 0
(-3975 5250);
DISPLAY 0.680851 (-3975 5250);
PAINT MONO (-3975 5250);
DISPLAY INVISIBLE (-3975 5250);
FORCEPROP 2 LAST CDS_SEC 1
J 0
(-3975 5250);
DISPLAY 1.021277 (-3975 5250);
DISPLAY INVISIBLE (-3975 5250);
FORCEADD OFFPAGE..5
(-4250 5200);
FORCEPROP 2 LAST $XR0 266 
J 0
(-4535 5200);
DISPLAY 0.638298 (-4535 5200);
PAINT MONO (-4535 5200);
FORCEPROP 1 LAST COMMENT_BODY TRUE
J 0
(-4150 5125);
DISPLAY 0.872340 (-4150 5125);
PAINT GREEN (-4150 5125);
DISPLAY INVISIBLE (-4150 5125);
FORCEPROP 1 LAST OFFPAGE TRUE
J 0
(-3925 5075);
DISPLAY 0.872340 (-3925 5075);
PAINT GREEN (-3925 5075);
DISPLAY INVISIBLE (-3925 5075);
FORCEPROP 2 LAST CDS_LIB standard
J 0
(-4250 5200);
DISPLAY INVISIBLE (-4250 5200);
FORCEPROP 2 LAST PATH I36
J 0
(-4525 5250);
DISPLAY 1.021277 (-4525 5250);
DISPLAY INVISIBLE (-4525 5250);
FORCEADD Q_CAP..1
(-4250 5650);
FORCEPROP 1 LAST PART_NUMBER CH5222KEB01
J 0
(-4200 5475);
DISPLAY 0.617021 (-4200 5475);
PAINT BLUE (-4200 5475);
DISPLAY INVISIBLE (-4200 5475);
FORCEPROP 1 LAST VOLTAGE 10V
J 0
(-4200 5675);
DISPLAY 0.617021 (-4200 5675);
PAINT SKYBLUE (-4200 5675);
FORCEPROP 1 LAST VALUE 2.2UF
J 0
(-4200 5725);
DISPLAY 0.617021 (-4200 5725);
PAINT SKYBLUE (-4200 5725);
FORCEPROP 1 LAST TOLERANCE 10%
J 0
(-4200 5625);
DISPLAY 0.617021 (-4200 5625);
PAINT SKYBLUE (-4200 5625);
FORCEPROP 1 LAST MATERIAL X6S
J 0
(-4200 5575);
DISPLAY 0.617021 (-4200 5575);
PAINT SKYBLUE (-4200 5575);
FORCEPROP 1 LAST PACK_TYPE C0402
J 0
(-4200 5525);
DISPLAY 0.617021 (-4200 5525);
PAINT SKYBLUE (-4200 5525);
FORCEPROP 1 LAST LOCATION PC600
J 0
(-4200 5775);
DISPLAY 0.617021 (-4200 5775);
PAINT AQUA (-4200 5775);
FORCEPROP 1 LASTPIN (-4250 5750) $PN 1
J 0
(-4240 5730);
DISPLAY 0.617021 (-4240 5730);
PAINT MONO (-4240 5730);
FORCEPROP 1 LASTPIN (-4250 5550) $PN 2
J 0
(-4240 5530);
DISPLAY 0.617021 (-4240 5530);
PAINT MONO (-4240 5530);
FORCEPROP 2 LAST CDS_LIB pure_quanta
J 0
(-4250 5650);
DISPLAY INVISIBLE (-4250 5650);
FORCEPROP 1 LAST PATH I37
J 0
(-4200 5800);
DISPLAY 0.978723 (-4200 5800);
PAINT WHITE (-4200 5800);
DISPLAY INVISIBLE (-4200 5800);
FORCEPROP 1 LAST LOCATION PC600
J 0
(-4200 5825);
DISPLAY 1.021277 (-4200 5825);
PAINT AQUA (-4200 5825);
DISPLAY INVISIBLE (-4200 5825);
FORCEPROP 0 LAST $SEC 1
J 0
(-4200 5825);
DISPLAY 0.680851 (-4200 5825);
PAINT MONO (-4200 5825);
DISPLAY INVISIBLE (-4200 5825);
FORCEPROP 0 LAST CDS_SEC 1
J 0
(-4200 5825);
DISPLAY 1.021277 (-4200 5825);
DISPLAY INVISIBLE (-4200 5825);
FORCEADD UNIVERSAL_GND..1
(-4250 5400);
FORCEPROP 3 LASTPIN (-4250 5450) SIG_NAME GND\g
J 0
(-4240 5460);
DISPLAY 0.659574 (-4240 5460);
PAINT MONO (-4240 5460);
DISPLAY INVISIBLE (-4240 5460);
FORCEPROP 1 LAST HDL_POWER GND
J 1
(-4225 5325);
DISPLAY 0.872340 (-4225 5325);
PAINT GREEN (-4225 5325);
DISPLAY INVISIBLE (-4225 5325);
FORCEPROP 2 LAST CDS_LIB logical_power
J 0
(-4250 5400);
PAINT MONO (-4250 5400);
DISPLAY INVISIBLE (-4250 5400);
FORCEPROP 1 LAST PATH I38
J 0
(-4175 5400);
DISPLAY 0.872340 (-4175 5400);
PAINT AQUA (-4175 5400);
DISPLAY INVISIBLE (-4175 5400);
FORCEADD Q_RES..2
(-4250 6050);
FORCEPROP 1 LAST PART_NUMBER CS-2202FB01
J 0
(-4210 5925);
DISPLAY 0.617021 (-4210 5925);
PAINT BLUE (-4210 5925);
DISPLAY INVISIBLE (-4210 5925);
FORCEPROP 1 LAST WATTAGE 1/16W
J 0
(-4210 6025);
DISPLAY 0.617021 (-4210 6025);
PAINT SKYBLUE (-4210 6025);
FORCEPROP 1 LAST PACK_TYPE 0402LF
J 0
(-4210 5875);
DISPLAY 0.617021 (-4210 5875);
PAINT SKYBLUE (-4210 5875);
FORCEPROP 1 LAST VALUE 2.2
J 0
(-4205 6125);
DISPLAY 0.617021 (-4205 6125);
PAINT SKYBLUE (-4205 6125);
FORCEPROP 1 LAST TOLERANCE 1%
J 0
(-4205 6075);
DISPLAY 0.617021 (-4205 6075);
PAINT SKYBLUE (-4205 6075);
FORCEPROP 1 LAST MATERIAL CHIP
J 0
(-4210 5975);
DISPLAY 0.617021 (-4210 5975);
PAINT SKYBLUE (-4210 5975);
FORCEPROP 1 LAST LOCATION PR355
J 0
(-4205 6175);
DISPLAY 0.617021 (-4205 6175);
PAINT AQUA (-4205 6175);
FORCEPROP 1 LASTPIN (-4250 6150) $PN 1
J 0
(-4245 6112);
DISPLAY 0.617021 (-4245 6112);
PAINT MONO (-4245 6112);
FORCEPROP 1 LASTPIN (-4250 5950) $PN 2
J 0
(-4245 5960);
DISPLAY 0.617021 (-4245 5960);
PAINT MONO (-4245 5960);
FORCEPROP 2 LAST CDS_LIB pure_quanta
J 0
(-4250 6050);
DISPLAY INVISIBLE (-4250 6050);
FORCEPROP 1 LAST PATH I39
J 0
(-4200 6225);
DISPLAY 0.978723 (-4200 6225);
PAINT WHITE (-4200 6225);
DISPLAY INVISIBLE (-4200 6225);
FORCEPROP 1 LAST LOCATION PR355
J 0
(-4200 6225);
DISPLAY 1.021277 (-4200 6225);
PAINT AQUA (-4200 6225);
DISPLAY INVISIBLE (-4200 6225);
FORCEPROP 0 LAST $SEC 1
J 0
(-4200 6225);
DISPLAY 0.680851 (-4200 6225);
PAINT MONO (-4200 6225);
DISPLAY INVISIBLE (-4200 6225);
FORCEPROP 0 LAST CDS_SEC 1
J 0
(-4200 6225);
DISPLAY 1.021277 (-4200 6225);
DISPLAY INVISIBLE (-4200 6225);
FORCEADD Q_RES..2
(-4825 3900);
FORCEPROP 1 LAST PART_NUMBER CS00002JB13
J 0
(-4785 3775);
DISPLAY 0.617021 (-4785 3775);
PAINT BLUE (-4785 3775);
DISPLAY INVISIBLE (-4785 3775);
FORCEPROP 1 LAST VALUE 0
J 0
(-4780 3975);
DISPLAY 0.617021 (-4780 3975);
PAINT SKYBLUE (-4780 3975);
FORCEPROP 1 LAST TOLERANCE 5%
J 0
(-4780 3925);
DISPLAY 0.617021 (-4780 3925);
PAINT SKYBLUE (-4780 3925);
FORCEPROP 1 LAST MATERIAL CHIP
J 0
(-4785 3825);
DISPLAY 0.617021 (-4785 3825);
PAINT SKYBLUE (-4785 3825);
FORCEPROP 1 LAST WATTAGE 1/16W
J 0
(-4785 3875);
DISPLAY 0.617021 (-4785 3875);
PAINT SKYBLUE (-4785 3875);
FORCEPROP 1 LAST PACK_TYPE 0402LF
J 0
(-4785 3725);
DISPLAY 0.617021 (-4785 3725);
PAINT SKYBLUE (-4785 3725);
FORCEPROP 1 LAST LOCATION PR447
J 0
(-4780 4025);
DISPLAY 0.617021 (-4780 4025);
PAINT AQUA (-4780 4025);
FORCEPROP 2 LAST CDS_LIB pure_quanta
J 0
(-4825 3900);
DISPLAY INVISIBLE (-4825 3900);
FORCEPROP 1 LAST PATH I4
J 0
(-4775 4075);
DISPLAY 0.978723 (-4775 4075);
PAINT WHITE (-4775 4075);
DISPLAY INVISIBLE (-4775 4075);
FORCEPROP 0 LAST $SEC 1
J 0
(-4775 4075);
DISPLAY INVISIBLE (-4775 4075);
FORCEPROP 0 LAST CDS_SEC 1
J 0
(-4775 4075);
DISPLAY INVISIBLE (-4775 4075);
FORCEPROP 1 LASTPIN (-4825 4000) $PN 1
J 0
(-4820 3962);
DISPLAY 0.787234 (-4820 3962);
PAINT MONO (-4820 3962);
DISPLAY INVISIBLE (-4820 3962);
FORCEPROP 1 LASTPIN (-4825 3800) $PN 2
J 0
(-4820 3810);
DISPLAY 0.787234 (-4820 3810);
PAINT MONO (-4820 3810);
DISPLAY INVISIBLE (-4820 3810);
FORCEADD Q_RES..2
(-4175 6700);
FORCEPROP 1 LAST PART_NUMBER CS00002JB13
J 0
(-4135 6575);
DISPLAY 0.617021 (-4135 6575);
PAINT BLUE (-4135 6575);
DISPLAY INVISIBLE (-4135 6575);
FORCEPROP 1 LAST PACK_TYPE 0402LF
J 0
(-4135 6525);
DISPLAY 0.617021 (-4135 6525);
PAINT SKYBLUE (-4135 6525);
FORCEPROP 1 LAST VALUE 0
J 0
(-4130 6775);
DISPLAY 0.617021 (-4130 6775);
PAINT SKYBLUE (-4130 6775);
FORCEPROP 1 LAST TOLERANCE 5%
J 0
(-4130 6725);
DISPLAY 0.617021 (-4130 6725);
PAINT SKYBLUE (-4130 6725);
FORCEPROP 1 LAST MATERIAL EMPTY
J 0
(-4135 6625);
DISPLAY 0.617021 (-4135 6625);
PAINT RED (-4135 6625);
FORCEPROP 1 LAST WATTAGE 1/16W
J 0
(-4135 6675);
DISPLAY 0.617021 (-4135 6675);
PAINT SKYBLUE (-4135 6675);
FORCEPROP 1 LAST LOCATION PR632
J 0
(-4130 6825);
DISPLAY 0.617021 (-4130 6825);
PAINT AQUA (-4130 6825);
FORCEPROP 2 LAST CDS_LIB pure_quanta
J 0
(-4175 6700);
DISPLAY INVISIBLE (-4175 6700);
FORCEPROP 1 LAST PATH I40
J 0
(-4125 6875);
DISPLAY 0.978723 (-4125 6875);
PAINT WHITE (-4125 6875);
DISPLAY INVISIBLE (-4125 6875);
FORCEPROP 0 LAST $SEC 1
J 0
(-4125 6875);
DISPLAY INVISIBLE (-4125 6875);
FORCEPROP 0 LAST CDS_SEC 1
J 0
(-4125 6875);
DISPLAY INVISIBLE (-4125 6875);
FORCEPROP 1 LASTPIN (-4175 6800) $PN 1
J 0
(-4170 6762);
DISPLAY 0.787234 (-4170 6762);
PAINT MONO (-4170 6762);
DISPLAY INVISIBLE (-4170 6762);
FORCEPROP 1 LASTPIN (-4175 6600) $PN 2
J 0
(-4170 6610);
DISPLAY 0.787234 (-4170 6610);
PAINT MONO (-4170 6610);
DISPLAY INVISIBLE (-4170 6610);
FORCEADD UNIVERSAL_GND..1
(-3725 5800);
FORCEPROP 3 LASTPIN (-3725 5850) SIG_NAME GND\g
J 0
(-3715 5860);
DISPLAY 0.659574 (-3715 5860);
PAINT MONO (-3715 5860);
DISPLAY INVISIBLE (-3715 5860);
FORCEPROP 1 LAST HDL_POWER GND
J 1
(-3700 5725);
DISPLAY 0.872340 (-3700 5725);
PAINT GREEN (-3700 5725);
DISPLAY INVISIBLE (-3700 5725);
FORCEPROP 2 LAST CDS_LIB logical_power
J 0
(-3725 5800);
PAINT MONO (-3725 5800);
DISPLAY INVISIBLE (-3725 5800);
FORCEPROP 1 LAST PATH I41
J 0
(-3650 5800);
DISPLAY 0.872340 (-3650 5800);
PAINT AQUA (-3650 5800);
DISPLAY INVISIBLE (-3650 5800);
FORCEADD Q_CAP..1
(-3725 6050);
FORCEPROP 1 LAST PART_NUMBER CH5222KEB01
J 0
(-3675 5900);
DISPLAY 0.617021 (-3675 5900);
PAINT BLUE (-3675 5900);
DISPLAY INVISIBLE (-3675 5900);
FORCEPROP 1 LAST VOLTAGE 10V
J 0
(-3675 6050);
DISPLAY 0.617021 (-3675 6050);
PAINT SKYBLUE (-3675 6050);
FORCEPROP 1 LAST TOLERANCE 10%
J 0
(-3675 6000);
DISPLAY 0.617021 (-3675 6000);
PAINT SKYBLUE (-3675 6000);
FORCEPROP 1 LAST PACK_TYPE C0402
J 0
(-3675 5850);
DISPLAY 0.617021 (-3675 5850);
PAINT SKYBLUE (-3675 5850);
FORCEPROP 1 LAST MATERIAL X6S
J 0
(-3675 5950);
DISPLAY 0.617021 (-3675 5950);
PAINT SKYBLUE (-3675 5950);
FORCEPROP 1 LAST VALUE 2.2UF
J 0
(-3675 6100);
DISPLAY 0.617021 (-3675 6100);
PAINT SKYBLUE (-3675 6100);
FORCEPROP 1 LAST LOCATION PC1211_P0_1
J 0
(-3675 6150);
DISPLAY 0.617021 (-3675 6150);
PAINT AQUA (-3675 6150);
FORCEPROP 1 LASTPIN (-3725 6150) $PN 1
J 0
(-3715 6130);
DISPLAY 0.617021 (-3715 6130);
FORCEPROP 1 LASTPIN (-3725 5950) $PN 2
J 0
(-3715 5930);
DISPLAY 0.617021 (-3715 5930);
FORCEPROP 2 LAST CDS_LIB pure_quanta
J 0
(-3725 6050);
PAINT MONO (-3725 6050);
DISPLAY INVISIBLE (-3725 6050);
FORCEPROP 1 LAST PATH I42
J 0
(-3675 6200);
DISPLAY 0.978723 (-3675 6200);
PAINT WHITE (-3675 6200);
DISPLAY INVISIBLE (-3675 6200);
FORCEPROP 2 LAST $SEC 1
J 0
(-3675 6250);
DISPLAY 0.680851 (-3675 6250);
PAINT MONO (-3675 6250);
DISPLAY INVISIBLE (-3675 6250);
FORCEPROP 2 LAST CDS_SEC 1
J 0
(-3675 6250);
DISPLAY 1.021277 (-3675 6250);
DISPLAY INVISIBLE (-3675 6250);
FORCEADD VCC15..1
(-4175 6925);
FORCEPROP 3 LASTPIN (-4175 6875) SIG_NAME P3V3\g
J 0
(-4165 6885);
DISPLAY 0.659574 (-4165 6885);
PAINT MONO (-4165 6885);
DISPLAY INVISIBLE (-4165 6885);
FORCEPROP 1 LAST HDL_POWER P3V3
J 1
(-4175 6975);
DISPLAY 0.617021 (-4175 6975);
PAINT GREEN (-4175 6975);
FORCEPROP 2 LAST CDS_LIB logical_power
J 0
(-4175 6925);
DISPLAY INVISIBLE (-4175 6925);
FORCEPROP 1 LAST PATH I43
J 0
(-4125 6950);
DISPLAY 0.872340 (-4125 6950);
PAINT AQUA (-4125 6950);
DISPLAY INVISIBLE (-4125 6950);
FORCEADD Q_CAP..1
(-1925 6100);
FORCEPROP 1 LAST PART_NUMBER TMP_QCH2336K1B12
J 0
(-1875 5950);
DISPLAY 0.617021 (-1875 5950);
PAINT BLUE (-1875 5950);
DISPLAY INVISIBLE (-1875 5950);
FORCEPROP 1 LAST PACK_TYPE 0402
J 0
(-1875 6000);
DISPLAY 0.617021 (-1875 6000);
PAINT SKYBLUE (-1875 6000);
FORCEPROP 1 LAST VOLTAGE 50V
J 0
(-1875 6150);
DISPLAY 0.617021 (-1875 6150);
PAINT SKYBLUE (-1875 6150);
FORCEPROP 1 LAST VALUE 3300PF
J 0
(-1875 6200);
DISPLAY 0.617021 (-1875 6200);
PAINT SKYBLUE (-1875 6200);
FORCEPROP 1 LAST TOLERANCE 10%
J 0
(-1875 6100);
DISPLAY 0.617021 (-1875 6100);
PAINT SKYBLUE (-1875 6100);
FORCEPROP 1 LAST MATERIAL X7R
J 0
(-1875 6050);
DISPLAY 0.617021 (-1875 6050);
PAINT SKYBLUE (-1875 6050);
FORCEPROP 1 LAST LOCATION PC602_P0_1
J 0
(-1875 6250);
DISPLAY 0.617021 (-1875 6250);
PAINT AQUA (-1875 6250);
FORCEPROP 1 LASTPIN (-1925 6200) $PN 1
J 0
(-1915 6180);
DISPLAY 0.617021 (-1915 6180);
PAINT MONO (-1915 6180);
FORCEPROP 1 LASTPIN (-1925 6000) $PN 2
J 0
(-1915 5980);
DISPLAY 0.617021 (-1915 5980);
PAINT MONO (-1915 5980);
FORCEPROP 2 LAST CDS_LIB pure_quanta
J 0
(-1925 6100);
DISPLAY INVISIBLE (-1925 6100);
FORCEPROP 1 LAST PATH I44
J 0
(-1875 6250);
DISPLAY 0.978723 (-1875 6250);
PAINT WHITE (-1875 6250);
DISPLAY INVISIBLE (-1875 6250);
FORCEPROP 1 LAST LOCATION PC602_P0_1
J 0
(-1875 6300);
DISPLAY 1.021277 (-1875 6300);
PAINT AQUA (-1875 6300);
DISPLAY INVISIBLE (-1875 6300);
FORCEPROP 0 LAST $SEC 1
J 0
(-1875 6300);
DISPLAY 0.680851 (-1875 6300);
PAINT MONO (-1875 6300);
DISPLAY INVISIBLE (-1875 6300);
FORCEPROP 0 LAST CDS_SEC 1
J 0
(-1875 6300);
DISPLAY 1.021277 (-1875 6300);
DISPLAY INVISIBLE (-1875 6300);
FORCEADD Q_CAP..1
(-1525 6100);
FORCEPROP 1 LAST PART_NUMBER CH5103KEB01
J 0
(-1475 5950);
DISPLAY 0.617021 (-1475 5950);
PAINT BLUE (-1475 5950);
DISPLAY INVISIBLE (-1475 5950);
FORCEPROP 1 LAST VOLTAGE 16V
J 0
(-1475 6150);
DISPLAY 0.617021 (-1475 6150);
PAINT SKYBLUE (-1475 6150);
FORCEPROP 1 LAST VALUE 1UF
J 0
(-1475 6200);
DISPLAY 0.617021 (-1475 6200);
PAINT SKYBLUE (-1475 6200);
FORCEPROP 1 LAST PACK_TYPE C0402
J 0
(-1475 6000);
DISPLAY 0.617021 (-1475 6000);
PAINT SKYBLUE (-1475 6000);
FORCEPROP 1 LAST TOLERANCE 10%
J 0
(-1475 6100);
DISPLAY 0.617021 (-1475 6100);
PAINT SKYBLUE (-1475 6100);
FORCEPROP 1 LAST MATERIAL X6S
J 0
(-1475 6050);
DISPLAY 0.617021 (-1475 6050);
PAINT SKYBLUE (-1475 6050);
FORCEPROP 1 LAST LOCATION PC604_P0_1
J 0
(-1475 6250);
DISPLAY 0.617021 (-1475 6250);
PAINT AQUA (-1475 6250);
FORCEPROP 1 LASTPIN (-1525 6200) $PN 1
J 0
(-1515 6180);
DISPLAY 0.617021 (-1515 6180);
PAINT MONO (-1515 6180);
FORCEPROP 1 LASTPIN (-1525 6000) $PN 2
J 0
(-1515 5980);
DISPLAY 0.617021 (-1515 5980);
PAINT MONO (-1515 5980);
FORCEPROP 2 LAST CDS_LIB pure_quanta
J 0
(-1525 6100);
DISPLAY INVISIBLE (-1525 6100);
FORCEPROP 1 LAST PATH I45
J 0
(-1475 6250);
DISPLAY 0.978723 (-1475 6250);
PAINT WHITE (-1475 6250);
DISPLAY INVISIBLE (-1475 6250);
FORCEPROP 1 LAST LOCATION PC604_P0_1
J 0
(-1475 6300);
DISPLAY 1.021277 (-1475 6300);
PAINT AQUA (-1475 6300);
DISPLAY INVISIBLE (-1475 6300);
FORCEPROP 0 LAST $SEC 1
J 0
(-1475 6300);
DISPLAY 0.680851 (-1475 6300);
PAINT MONO (-1475 6300);
DISPLAY INVISIBLE (-1475 6300);
FORCEPROP 0 LAST CDS_SEC 1
J 0
(-1475 6300);
DISPLAY 1.021277 (-1475 6300);
DISPLAY INVISIBLE (-1475 6300);
FORCEADD Q_RES..1
(-1225 5650);
FORCEPROP 1 LAST PART_NUMBER CS-3302FB01
J 0
(-1325 5700);
DISPLAY 0.617021 (-1325 5700);
PAINT BLUE (-1325 5700);
DISPLAY INVISIBLE (-1325 5700);
FORCEPROP 1 LAST WATTAGE 1/16W
J 2
(-1100 5725);
DISPLAY 0.617021 (-1100 5725);
PAINT SKYBLUE (-1100 5725);
FORCEPROP 1 LAST PACK_TYPE 0402LF
J 0
(-1325 5725);
DISPLAY 0.617021 (-1325 5725);
PAINT SKYBLUE (-1325 5725);
FORCEPROP 1 LAST MATERIAL CHIP
J 0
(-1325 5750);
DISPLAY 0.617021 (-1325 5750);
PAINT SKYBLUE (-1325 5750);
FORCEPROP 1 LAST VALUE 3.3
J 2
(-1000 5650);
DISPLAY 0.617021 (-1000 5650);
PAINT SKYBLUE (-1000 5650);
FORCEPROP 1 LAST TOLERANCE 1%
J 0
(-975 5650);
DISPLAY 0.617021 (-975 5650);
PAINT SKYBLUE (-975 5650);
FORCEPROP 1 LAST LOCATION PR1780
J 0
(-1475 5650);
DISPLAY 0.617021 (-1475 5650);
PAINT AQUA (-1475 5650);
FORCEPROP 1 LASTPIN (-1325 5650) $PN 1
J 0
(-1313 5662);
DISPLAY 0.617021 (-1313 5662);
FORCEPROP 1 LASTPIN (-1125 5650) $PN 2
J 0
(-1163 5662);
DISPLAY 0.617021 (-1163 5662);
FORCEPROP 2 LAST CDS_LIB pure_quanta
J 0
(-1225 5650);
PAINT MONO (-1225 5650);
DISPLAY INVISIBLE (-1225 5650);
FORCEPROP 1 LAST PATH I46
J 0
(-1275 5800);
DISPLAY 0.978723 (-1275 5800);
PAINT WHITE (-1275 5800);
DISPLAY INVISIBLE (-1275 5800);
FORCEPROP 2 LAST $SEC 1
J 0
(-1275 5850);
DISPLAY 0.680851 (-1275 5850);
PAINT MONO (-1275 5850);
DISPLAY INVISIBLE (-1275 5850);
FORCEPROP 2 LAST CDS_SEC 1
J 0
(-1275 5850);
DISPLAY 1.021277 (-1275 5850);
DISPLAY INVISIBLE (-1275 5850);
FORCEADD Q_CAP..1
(-1125 6100);
FORCEPROP 1 LAST PART_NUMBER CH6223MEA01
J 0
(-1075 5950);
DISPLAY 0.617021 (-1075 5950);
PAINT BLUE (-1075 5950);
DISPLAY INVISIBLE (-1075 5950);
FORCEPROP 1 LAST TOLERANCE 20%
J 0
(-1075 6100);
DISPLAY 0.617021 (-1075 6100);
PAINT SKYBLUE (-1075 6100);
FORCEPROP 1 LAST VOLTAGE 16V
J 0
(-1075 6150);
DISPLAY 0.617021 (-1075 6150);
PAINT SKYBLUE (-1075 6150);
FORCEPROP 1 LAST VALUE 22UF
J 0
(-1075 6200);
DISPLAY 0.617021 (-1075 6200);
PAINT SKYBLUE (-1075 6200);
FORCEPROP 1 LAST PACK_TYPE C0805
J 0
(-1075 6000);
DISPLAY 0.617021 (-1075 6000);
PAINT SKYBLUE (-1075 6000);
FORCEPROP 1 LAST MATERIAL X6S
J 0
(-1075 6050);
DISPLAY 0.617021 (-1075 6050);
PAINT SKYBLUE (-1075 6050);
FORCEPROP 1 LAST LOCATION PC608_P0_1
J 0
(-1075 6250);
DISPLAY 0.617021 (-1075 6250);
PAINT AQUA (-1075 6250);
FORCEPROP 1 LASTPIN (-1125 6200) $PN 1
J 0
(-1115 6180);
DISPLAY 0.617021 (-1115 6180);
PAINT MONO (-1115 6180);
FORCEPROP 1 LASTPIN (-1125 6000) $PN 2
J 0
(-1115 5980);
DISPLAY 0.617021 (-1115 5980);
PAINT MONO (-1115 5980);
FORCEPROP 2 LAST CDS_LIB pure_quanta
J 0
(-1125 6100);
DISPLAY INVISIBLE (-1125 6100);
FORCEPROP 1 LAST PATH I47
J 0
(-1075 6250);
DISPLAY 0.978723 (-1075 6250);
PAINT WHITE (-1075 6250);
DISPLAY INVISIBLE (-1075 6250);
FORCEPROP 1 LAST LOCATION PC608_P0_1
J 0
(-1075 6300);
DISPLAY 1.021277 (-1075 6300);
PAINT AQUA (-1075 6300);
DISPLAY INVISIBLE (-1075 6300);
FORCEPROP 0 LAST $SEC 1
J 0
(-1075 6300);
DISPLAY 0.680851 (-1075 6300);
PAINT MONO (-1075 6300);
DISPLAY INVISIBLE (-1075 6300);
FORCEPROP 0 LAST CDS_SEC 1
J 0
(-1075 6300);
DISPLAY 1.021277 (-1075 6300);
DISPLAY INVISIBLE (-1075 6300);
FORCEADD Q_CAP..1
(-725 6100);
FORCEPROP 1 LAST PART_NUMBER CH6223MEA01
J 0
(-675 5950);
DISPLAY 0.617021 (-675 5950);
PAINT BLUE (-675 5950);
DISPLAY INVISIBLE (-675 5950);
FORCEPROP 1 LAST TOLERANCE 20%
J 0
(-675 6100);
DISPLAY 0.617021 (-675 6100);
PAINT SKYBLUE (-675 6100);
FORCEPROP 1 LAST VOLTAGE 16V
J 0
(-675 6150);
DISPLAY 0.617021 (-675 6150);
PAINT SKYBLUE (-675 6150);
FORCEPROP 1 LAST PACK_TYPE C0805
J 0
(-675 6000);
DISPLAY 0.617021 (-675 6000);
PAINT SKYBLUE (-675 6000);
FORCEPROP 1 LAST MATERIAL X6S
J 0
(-675 6050);
DISPLAY 0.617021 (-675 6050);
PAINT SKYBLUE (-675 6050);
FORCEPROP 1 LAST VALUE 22UF
J 0
(-675 6200);
DISPLAY 0.617021 (-675 6200);
PAINT SKYBLUE (-675 6200);
FORCEPROP 1 LAST LOCATION PC610_P0_1
J 0
(-675 6250);
DISPLAY 0.617021 (-675 6250);
PAINT AQUA (-675 6250);
FORCEPROP 1 LASTPIN (-725 6200) $PN 1
J 0
(-715 6180);
DISPLAY 0.617021 (-715 6180);
PAINT MONO (-715 6180);
FORCEPROP 1 LASTPIN (-725 6000) $PN 2
J 0
(-715 5980);
DISPLAY 0.617021 (-715 5980);
PAINT MONO (-715 5980);
FORCEPROP 2 LAST CDS_LIB pure_quanta
J 0
(-725 6100);
DISPLAY INVISIBLE (-725 6100);
FORCEPROP 1 LAST PATH I48
J 0
(-675 6250);
DISPLAY 0.978723 (-675 6250);
PAINT WHITE (-675 6250);
DISPLAY INVISIBLE (-675 6250);
FORCEPROP 1 LAST LOCATION PC610_P0_1
J 0
(-675 6300);
DISPLAY 1.021277 (-675 6300);
PAINT AQUA (-675 6300);
DISPLAY INVISIBLE (-675 6300);
FORCEPROP 0 LAST $SEC 1
J 0
(-675 6300);
DISPLAY 0.680851 (-675 6300);
PAINT MONO (-675 6300);
DISPLAY INVISIBLE (-675 6300);
FORCEPROP 0 LAST CDS_SEC 1
J 0
(-675 6300);
DISPLAY 1.021277 (-675 6300);
DISPLAY INVISIBLE (-675 6300);
FORCEADD Q_INDUCTOR..1
(-25 2425);
FORCEPROP 1 LAST PART_NUMBER CV+13^0KZ11
J 0
(-150 2535);
DISPLAY 0.617021 (-150 2535);
PAINT BLUE (-150 2535);
DISPLAY INVISIBLE (-150 2535);
FORCEPROP 2 LAST PACK_TYPE SMLF
J 0
(-150 2625);
DISPLAY 0.617021 (-150 2625);
PAINT SKYBLUE (-150 2625);
FORCEPROP 2 LAST VALUE 130NH/106A
J 0
(-150 2675);
DISPLAY 0.617021 (-150 2675);
PAINT SKYBLUE (-150 2675);
FORCEPROP 1 LAST MATERIAL IND
J 0
(-150 2480);
DISPLAY 0.617021 (-150 2480);
PAINT SKYBLUE (-150 2480);
FORCEPROP 1 LAST LOCATION PL34
J 0
(-150 2585);
DISPLAY 0.617021 (-150 2585);
PAINT AQUA (-150 2585);
FORCEPROP 0 LASTPIN (-125 2400) $PN 1
J 2
(-135 2410);
DISPLAY 0.617021 (-135 2410);
PAINT MONO (-135 2410);
FORCEPROP 0 LASTPIN (75 2400) $PN 2
J 0
(85 2410);
DISPLAY 0.617021 (85 2410);
PAINT MONO (85 2410);
FORCEPROP 2 LAST CDS_LIB pure_quanta
J 0
(-25 2425);
DISPLAY INVISIBLE (-25 2425);
FORCEPROP 1 LAST NEEDS_NO_SIZE TRUE
J 0
(-25 2425);
DISPLAY 0.468085 (-25 2425);
PAINT GREEN (-25 2425);
DISPLAY INVISIBLE (-25 2425);
FORCEPROP 1 LAST PATH I49
J 0
(50 2480);
DISPLAY 0.723404 (50 2480);
PAINT GREEN (50 2480);
DISPLAY INVISIBLE (50 2480);
FORCEPROP 0 LAST $SEC 1
J 0
(-150 2725);
DISPLAY 0.680851 (-150 2725);
PAINT MONO (-150 2725);
DISPLAY INVISIBLE (-150 2725);
FORCEPROP 0 LAST CDS_SEC 1
J 0
(-150 2725);
DISPLAY 1.021277 (-150 2725);
DISPLAY INVISIBLE (-150 2725);
FORCEADD VCC15..1
(-4825 4125);
FORCEPROP 3 LASTPIN (-4825 4075) SIG_NAME P5V\g
J 0
(-4815 4085);
DISPLAY 0.659574 (-4815 4085);
PAINT MONO (-4815 4085);
DISPLAY INVISIBLE (-4815 4085);
FORCEPROP 1 LAST HDL_POWER P5V
J 1
(-4825 4175);
DISPLAY 0.617021 (-4825 4175);
PAINT GREEN (-4825 4175);
FORCEPROP 2 LAST CDS_LIB logical_power
J 0
(-4825 4125);
DISPLAY INVISIBLE (-4825 4125);
FORCEPROP 1 LAST PATH I5
J 0
(-4775 4150);
DISPLAY 0.872340 (-4775 4150);
PAINT AQUA (-4775 4150);
DISPLAY INVISIBLE (-4775 4150);
FORCEADD Q_RES..1
(-25 2150);
FORCEPROP 1 LAST PART_NUMBER CS00002JB13
J 0
(-125 2100);
DISPLAY 0.617021 (-125 2100);
PAINT BLUE (-125 2100);
DISPLAY INVISIBLE (-125 2100);
FORCEPROP 1 LAST PACK_TYPE 0402LF
J 0
(-25 2050);
DISPLAY 0.617021 (-25 2050);
PAINT SKYBLUE (-25 2050);
FORCEPROP 1 LAST VALUE 0
J 2
(125 2150);
DISPLAY 0.617021 (125 2150);
PAINT SKYBLUE (125 2150);
FORCEPROP 1 LAST TOLERANCE 5%
J 0
(150 2150);
DISPLAY 0.617021 (150 2150);
PAINT SKYBLUE (150 2150);
FORCEPROP 1 LAST MATERIAL CHIP
J 0
(-125 2050);
DISPLAY 0.617021 (-125 2050);
PAINT SKYBLUE (-125 2050);
FORCEPROP 1 LAST WATTAGE 1/16W
J 2
(200 2050);
DISPLAY 0.617021 (200 2050);
PAINT SKYBLUE (200 2050);
FORCEPROP 1 LAST LOCATION PR1323
J 0
(-275 2150);
DISPLAY 0.617021 (-275 2150);
PAINT AQUA (-275 2150);
FORCEPROP 1 LASTPIN (-125 2150) $PN 1
J 0
(-113 2162);
DISPLAY 0.617021 (-113 2162);
FORCEPROP 1 LASTPIN (75 2150) $PN 2
J 0
(37 2162);
DISPLAY 0.617021 (37 2162);
FORCEPROP 2 LAST CDS_LIB pure_quanta
J 0
(-25 2150);
PAINT MONO (-25 2150);
DISPLAY INVISIBLE (-25 2150);
FORCEPROP 1 LAST PATH I50
J 0
(-75 2300);
DISPLAY 0.978723 (-75 2300);
PAINT WHITE (-75 2300);
DISPLAY INVISIBLE (-75 2300);
FORCEPROP 2 LAST $SEC 1
J 0
(-75 2350);
DISPLAY 0.680851 (-75 2350);
PAINT MONO (-75 2350);
DISPLAY INVISIBLE (-75 2350);
FORCEPROP 2 LAST CDS_SEC 1
J 0
(-75 2350);
DISPLAY 1.021277 (-75 2350);
DISPLAY INVISIBLE (-75 2350);
FORCEADD Q_CAP..1
(1000 2200);
FORCEPROP 1 LAST PART_NUMBER CH5103KEB01
J 0
(1050 2025);
DISPLAY 0.617021 (1050 2025);
PAINT BLUE (1050 2025);
DISPLAY INVISIBLE (1050 2025);
FORCEPROP 1 LAST VOLTAGE 16V
J 0
(1050 2225);
DISPLAY 0.617021 (1050 2225);
PAINT SKYBLUE (1050 2225);
FORCEPROP 1 LAST PACK_TYPE C0402
J 0
(1050 2075);
DISPLAY 0.617021 (1050 2075);
PAINT SKYBLUE (1050 2075);
FORCEPROP 1 LAST TOLERANCE 10%
J 0
(1050 2175);
DISPLAY 0.617021 (1050 2175);
PAINT SKYBLUE (1050 2175);
FORCEPROP 1 LAST MATERIAL X6S
J 0
(1050 2125);
DISPLAY 0.617021 (1050 2125);
PAINT SKYBLUE (1050 2125);
FORCEPROP 1 LAST VALUE 1UF
J 0
(1050 2275);
DISPLAY 0.617021 (1050 2275);
PAINT SKYBLUE (1050 2275);
FORCEPROP 1 LAST LOCATION PC613_P0_2
J 0
(1050 2325);
DISPLAY 0.617021 (1050 2325);
PAINT AQUA (1050 2325);
FORCEPROP 1 LASTPIN (1000 2300) $PN 1
J 0
(1010 2280);
DISPLAY 0.617021 (1010 2280);
PAINT MONO (1010 2280);
FORCEPROP 1 LASTPIN (1000 2100) $PN 2
J 0
(1010 2080);
DISPLAY 0.617021 (1010 2080);
PAINT MONO (1010 2080);
FORCEPROP 2 LAST CDS_LIB pure_quanta
J 0
(1000 2200);
DISPLAY INVISIBLE (1000 2200);
FORCEPROP 1 LAST PATH I51
J 0
(1050 2350);
DISPLAY 0.978723 (1050 2350);
PAINT WHITE (1050 2350);
DISPLAY INVISIBLE (1050 2350);
FORCEPROP 1 LAST LOCATION PC613_P0_2
J 0
(1050 2375);
DISPLAY 1.021277 (1050 2375);
PAINT AQUA (1050 2375);
DISPLAY INVISIBLE (1050 2375);
FORCEPROP 0 LAST $SEC 1
J 0
(1050 2375);
DISPLAY 0.680851 (1050 2375);
PAINT MONO (1050 2375);
DISPLAY INVISIBLE (1050 2375);
FORCEPROP 0 LAST CDS_SEC 1
J 0
(1050 2375);
DISPLAY 1.021277 (1050 2375);
DISPLAY INVISIBLE (1050 2375);
FORCEADD Q_CAP..1
(1450 2200);
FORCEPROP 1 LAST PART_NUMBER CH622KMEA03
J 0
(1500 2025);
DISPLAY 0.617021 (1500 2025);
PAINT BLUE (1500 2025);
DISPLAY INVISIBLE (1500 2025);
FORCEPROP 1 LAST TOLERANCE 20%
J 0
(1500 2175);
DISPLAY 0.617021 (1500 2175);
PAINT SKYBLUE (1500 2175);
FORCEPROP 1 LAST MATERIAL X6S
J 0
(1500 2125);
DISPLAY 0.617021 (1500 2125);
PAINT SKYBLUE (1500 2125);
FORCEPROP 1 LAST VOLTAGE 4V
J 0
(1500 2225);
DISPLAY 0.617021 (1500 2225);
PAINT SKYBLUE (1500 2225);
FORCEPROP 1 LAST VALUE 22UF
J 0
(1500 2275);
DISPLAY 0.617021 (1500 2275);
PAINT SKYBLUE (1500 2275);
FORCEPROP 1 LAST PACK_TYPE C0805
J 0
(1500 2075);
DISPLAY 0.617021 (1500 2075);
PAINT SKYBLUE (1500 2075);
FORCEPROP 1 LAST LOCATION PC616_P0_2
J 0
(1500 2325);
DISPLAY 0.617021 (1500 2325);
PAINT AQUA (1500 2325);
FORCEPROP 1 LASTPIN (1450 2300) $PN 1
J 0
(1460 2280);
DISPLAY 0.617021 (1460 2280);
PAINT MONO (1460 2280);
FORCEPROP 1 LASTPIN (1450 2100) $PN 2
J 0
(1460 2080);
DISPLAY 0.617021 (1460 2080);
PAINT MONO (1460 2080);
FORCEPROP 2 LAST CDS_LIB pure_quanta
J 0
(1450 2200);
DISPLAY INVISIBLE (1450 2200);
FORCEPROP 1 LAST PATH I52
J 0
(1500 2350);
DISPLAY 0.978723 (1500 2350);
PAINT WHITE (1500 2350);
DISPLAY INVISIBLE (1500 2350);
FORCEPROP 1 LAST LOCATION PC616_P0_2
J 0
(1500 2375);
DISPLAY 1.021277 (1500 2375);
PAINT AQUA (1500 2375);
DISPLAY INVISIBLE (1500 2375);
FORCEPROP 0 LAST $SEC 1
J 0
(1500 2375);
DISPLAY 0.680851 (1500 2375);
PAINT MONO (1500 2375);
DISPLAY INVISIBLE (1500 2375);
FORCEPROP 0 LAST CDS_SEC 1
J 0
(1500 2375);
DISPLAY 1.021277 (1500 2375);
DISPLAY INVISIBLE (1500 2375);
FORCEADD Q_CAP..1
R 2
(-300 2675);
FORCEPROP 1 LAST PART_NUMBER CH4106K1B01
J 2
(-350 2600);
DISPLAY 0.617021 (-350 2600);
PAINT BLUE (-350 2600);
DISPLAY INVISIBLE (-350 2600);
FORCEPROP 1 LAST PACK_TYPE C0402
J 2
(-350 2575);
DISPLAY 0.617021 (-350 2575);
PAINT SKYBLUE (-350 2575);
FORCEPROP 1 LAST VOLTAGE 50V
J 2
(-350 2675);
DISPLAY 0.617021 (-350 2675);
PAINT SKYBLUE (-350 2675);
FORCEPROP 1 LAST VALUE 100NF
J 2
(-350 2700);
DISPLAY 0.617021 (-350 2700);
PAINT SKYBLUE (-350 2700);
FORCEPROP 1 LAST TOLERANCE 10%
J 2
(-350 2650);
DISPLAY 0.617021 (-350 2650);
PAINT SKYBLUE (-350 2650);
FORCEPROP 1 LAST MATERIAL X7R
J 2
(-350 2625);
DISPLAY 0.617021 (-350 2625);
PAINT SKYBLUE (-350 2625);
FORCEPROP 1 LAST LOCATION PC607
J 2
(-350 2750);
DISPLAY 0.617021 (-350 2750);
PAINT AQUA (-350 2750);
FORCEPROP 1 LASTPIN (-300 2775) $PN 1
J 2
(-310 2755);
DISPLAY 0.617021 (-310 2755);
FORCEPROP 1 LASTPIN (-300 2575) $PN 2
J 2
(-310 2555);
DISPLAY 0.617021 (-310 2555);
FORCEPROP 2 LAST CDS_LIB pure_quanta
J 2
(-300 2675);
PAINT MONO (-300 2675);
DISPLAY INVISIBLE (-300 2675);
FORCEPROP 1 LAST PATH I53
J 2
(-350 2825);
DISPLAY 0.978723 (-350 2825);
PAINT WHITE (-350 2825);
DISPLAY INVISIBLE (-350 2825);
FORCEPROP 2 LAST $SEC 1
J 0
(-350 2875);
DISPLAY 0.680851 (-350 2875);
PAINT MONO (-350 2875);
DISPLAY INVISIBLE (-350 2875);
FORCEPROP 2 LAST CDS_SEC 1
J 0
(-350 2875);
DISPLAY 1.021277 (-350 2875);
DISPLAY INVISIBLE (-350 2875);
FORCEADD UNIVERSAL_GND..1
(-125 2925);
FORCEPROP 3 LASTPIN (-125 2975) SIG_NAME GND\g
J 0
(-115 2985);
DISPLAY 0.659574 (-115 2985);
PAINT MONO (-115 2985);
DISPLAY INVISIBLE (-115 2985);
FORCEPROP 1 LAST HDL_POWER GND
J 1
(-100 2850);
DISPLAY 0.872340 (-100 2850);
PAINT GREEN (-100 2850);
DISPLAY INVISIBLE (-100 2850);
FORCEPROP 2 LAST CDS_LIB logical_power
J 0
(-125 2925);
PAINT MONO (-125 2925);
DISPLAY INVISIBLE (-125 2925);
FORCEPROP 1 LAST PATH I54
J 0
(-50 2925);
DISPLAY 0.872340 (-50 2925);
PAINT AQUA (-50 2925);
DISPLAY INVISIBLE (-50 2925);
FORCEADD Q_CAP..1
(-250 3300);
FORCEPROP 1 LAST PART_NUMBER CH6223MEA01
J 0
(-200 3150);
DISPLAY 0.617021 (-200 3150);
PAINT BLUE (-200 3150);
DISPLAY INVISIBLE (-200 3150);
FORCEPROP 1 LAST TOLERANCE 20%
J 0
(-200 3250);
DISPLAY 0.617021 (-200 3250);
PAINT SKYBLUE (-200 3250);
FORCEPROP 1 LAST MATERIAL X6S
J 0
(-200 3200);
DISPLAY 0.617021 (-200 3200);
PAINT SKYBLUE (-200 3200);
FORCEPROP 1 LAST VALUE 22UF
J 0
(-200 3350);
DISPLAY 0.617021 (-200 3350);
PAINT SKYBLUE (-200 3350);
FORCEPROP 1 LAST VOLTAGE 16V
J 0
(-200 3300);
DISPLAY 0.617021 (-200 3300);
PAINT SKYBLUE (-200 3300);
FORCEPROP 1 LAST PACK_TYPE C0805
J 0
(-200 3100);
DISPLAY 0.617021 (-200 3100);
PAINT SKYBLUE (-200 3100);
FORCEPROP 1 LAST LOCATION PC721_P0_2
J 0
(-200 3400);
DISPLAY 0.617021 (-200 3400);
PAINT AQUA (-200 3400);
FORCEPROP 1 LASTPIN (-250 3400) $PN 1
J 0
(-240 3380);
DISPLAY 0.787234 (-240 3380);
PAINT MONO (-240 3380);
FORCEPROP 1 LASTPIN (-250 3200) $PN 2
J 0
(-240 3180);
DISPLAY 0.787234 (-240 3180);
PAINT MONO (-240 3180);
FORCEPROP 2 LAST CDS_LIB pure_quanta
J 0
(-250 3300);
DISPLAY INVISIBLE (-250 3300);
FORCEPROP 1 LAST PATH I55
J 0
(-200 3450);
DISPLAY 0.978723 (-200 3450);
PAINT WHITE (-200 3450);
DISPLAY INVISIBLE (-200 3450);
FORCEPROP 0 LAST $SEC 1
J 0
(-200 3450);
DISPLAY 0.680851 (-200 3450);
PAINT MONO (-200 3450);
DISPLAY INVISIBLE (-200 3450);
FORCEPROP 0 LAST CDS_SEC 1
J 0
(-200 3450);
DISPLAY 1.021277 (-200 3450);
DISPLAY INVISIBLE (-200 3450);
FORCEADD VCC15..1
(-125 3675);
FORCEPROP 3 LASTPIN (-125 3625) SIG_NAME SW_P12V_PVCCFA_EHV_FIVRA_CPU0_L\g
J 0
(-115 3635);
DISPLAY 0.659574 (-115 3635);
PAINT MONO (-115 3635);
DISPLAY INVISIBLE (-115 3635);
FORCEPROP 1 LAST HDL_POWER SW_P12V_PVCCFA_EHV_FIVRA_CPU0_L
J 1
(-75 3725);
DISPLAY 0.617021 (-75 3725);
PAINT GREEN (-75 3725);
FORCEPROP 2 LAST CDS_LIB logical_power
J 0
(-125 3675);
DISPLAY INVISIBLE (-125 3675);
FORCEPROP 1 LAST PATH I56
J 0
(-75 3700);
DISPLAY 0.872340 (-75 3700);
PAINT AQUA (-75 3700);
DISPLAY INVISIBLE (-75 3700);
FORCEADD Q_CAPP..1
(1175 3325);
FORCEPROP 1 LAST PART_NUMBER CC7560JMD16
J 0
(1225 3175);
DISPLAY 0.617021 (1225 3175);
PAINT BLUE (1225 3175);
DISPLAY INVISIBLE (1225 3175);
FORCEPROP 1 LAST PACK_TYPE THLF
J 0
(1225 3225);
DISPLAY 0.617021 (1225 3225);
PAINT SKYBLUE (1225 3225);
FORCEPROP 1 LAST VALUE 560UF
J 0
(1225 3425);
DISPLAY 0.617021 (1225 3425);
PAINT SKYBLUE (1225 3425);
FORCEPROP 1 LAST TOLERANCE 20%
J 0
(1225 3375);
DISPLAY 0.617021 (1225 3375);
PAINT SKYBLUE (1225 3375);
FORCEPROP 1 LAST MATERIAL OSCON
J 0
(1225 3275);
DISPLAY 0.617021 (1225 3275);
PAINT SKYBLUE (1225 3275);
FORCEPROP 1 LAST VOLTAGE 2.5V
J 0
(1225 3325);
DISPLAY 0.617021 (1225 3325);
PAINT SKYBLUE (1225 3325);
FORCEPROP 1 LAST LOCATION PC619
J 0
(1225 3475);
DISPLAY 0.617021 (1225 3475);
PAINT AQUA (1225 3475);
FORCEPROP 1 LASTPIN (1175 3425) $PN 1
J 0
(1185 3410);
DISPLAY 0.617021 (1185 3410);
PAINT MONO (1185 3410);
FORCEPROP 1 LASTPIN (1175 3225) $PN 2
J 0
(1185 3210);
DISPLAY 0.617021 (1185 3210);
PAINT MONO (1185 3210);
FORCEPROP 2 LAST CDS_LIB pure_quanta
J 0
(1175 3325);
DISPLAY INVISIBLE (1175 3325);
FORCEPROP 1 LAST PATH I57
J 0
(1225 3475);
DISPLAY 0.978723 (1225 3475);
DISPLAY INVISIBLE (1225 3475);
FORCEPROP 1 LAST LOCATION PC619
J 0
(1225 3525);
DISPLAY 1.021277 (1225 3525);
PAINT AQUA (1225 3525);
DISPLAY INVISIBLE (1225 3525);
FORCEPROP 0 LAST $SEC 1
J 0
(1225 3525);
DISPLAY 0.680851 (1225 3525);
PAINT MONO (1225 3525);
DISPLAY INVISIBLE (1225 3525);
FORCEPROP 0 LAST CDS_SEC 1
J 0
(1225 3525);
DISPLAY 1.021277 (1225 3525);
DISPLAY INVISIBLE (1225 3525);
FORCEADD Q_CAPP..1
(1700 3325);
FORCEPROP 1 LAST PART_NUMBER CC7560JMD16
J 0
(1750 3175);
DISPLAY 0.617021 (1750 3175);
PAINT BLUE (1750 3175);
DISPLAY INVISIBLE (1750 3175);
FORCEPROP 1 LAST PACK_TYPE THLF
J 0
(1750 3225);
DISPLAY 0.617021 (1750 3225);
PAINT SKYBLUE (1750 3225);
FORCEPROP 1 LAST VALUE 560UF
J 0
(1750 3425);
DISPLAY 0.617021 (1750 3425);
PAINT SKYBLUE (1750 3425);
FORCEPROP 1 LAST TOLERANCE 20%
J 0
(1750 3375);
DISPLAY 0.617021 (1750 3375);
PAINT SKYBLUE (1750 3375);
FORCEPROP 1 LAST MATERIAL OSCON
J 0
(1750 3275);
DISPLAY 0.617021 (1750 3275);
PAINT SKYBLUE (1750 3275);
FORCEPROP 1 LAST VOLTAGE 2.5V
J 0
(1750 3325);
DISPLAY 0.617021 (1750 3325);
PAINT SKYBLUE (1750 3325);
FORCEPROP 1 LAST LOCATION PC620
J 0
(1750 3475);
DISPLAY 0.617021 (1750 3475);
PAINT AQUA (1750 3475);
FORCEPROP 1 LASTPIN (1700 3425) $PN 1
J 0
(1710 3410);
DISPLAY 0.617021 (1710 3410);
PAINT MONO (1710 3410);
FORCEPROP 1 LASTPIN (1700 3225) $PN 2
J 0
(1710 3210);
DISPLAY 0.617021 (1710 3210);
PAINT MONO (1710 3210);
FORCEPROP 2 LAST CDS_LIB pure_quanta
J 0
(1700 3325);
DISPLAY INVISIBLE (1700 3325);
FORCEPROP 1 LAST PATH I58
J 0
(1750 3475);
DISPLAY 0.978723 (1750 3475);
DISPLAY INVISIBLE (1750 3475);
FORCEPROP 1 LAST LOCATION PC620
J 0
(1750 3525);
DISPLAY 1.021277 (1750 3525);
PAINT AQUA (1750 3525);
DISPLAY INVISIBLE (1750 3525);
FORCEPROP 0 LAST $SEC 1
J 0
(1750 3525);
DISPLAY 0.680851 (1750 3525);
PAINT MONO (1750 3525);
DISPLAY INVISIBLE (1750 3525);
FORCEPROP 0 LAST CDS_SEC 1
J 0
(1750 3525);
DISPLAY 1.021277 (1750 3525);
DISPLAY INVISIBLE (1750 3525);
FORCEADD Q_CAP..1
(1875 2200);
FORCEPROP 1 LAST PART_NUMBER CH622KMEA03
J 0
(1925 2025);
DISPLAY 0.617021 (1925 2025);
PAINT BLUE (1925 2025);
DISPLAY INVISIBLE (1925 2025);
FORCEPROP 1 LAST TOLERANCE 20%
J 0
(1925 2175);
DISPLAY 0.617021 (1925 2175);
PAINT SKYBLUE (1925 2175);
FORCEPROP 1 LAST VALUE 22UF
J 0
(1925 2275);
DISPLAY 0.617021 (1925 2275);
PAINT SKYBLUE (1925 2275);
FORCEPROP 1 LAST VOLTAGE 4V
J 0
(1925 2225);
DISPLAY 0.617021 (1925 2225);
PAINT SKYBLUE (1925 2225);
FORCEPROP 1 LAST PACK_TYPE C0805
J 0
(1925 2075);
DISPLAY 0.617021 (1925 2075);
PAINT SKYBLUE (1925 2075);
FORCEPROP 1 LAST MATERIAL X6S
J 0
(1925 2125);
DISPLAY 0.617021 (1925 2125);
PAINT SKYBLUE (1925 2125);
FORCEPROP 1 LAST LOCATION PC618_P0_2
J 0
(1925 2325);
DISPLAY 0.617021 (1925 2325);
PAINT AQUA (1925 2325);
FORCEPROP 1 LASTPIN (1875 2300) $PN 1
J 0
(1885 2280);
DISPLAY 0.617021 (1885 2280);
PAINT MONO (1885 2280);
FORCEPROP 1 LASTPIN (1875 2100) $PN 2
J 0
(1885 2080);
DISPLAY 0.617021 (1885 2080);
PAINT MONO (1885 2080);
FORCEPROP 2 LAST CDS_LIB pure_quanta
J 0
(1875 2200);
DISPLAY INVISIBLE (1875 2200);
FORCEPROP 1 LAST PATH I59
J 0
(1925 2350);
DISPLAY 0.978723 (1925 2350);
PAINT WHITE (1925 2350);
DISPLAY INVISIBLE (1925 2350);
FORCEPROP 1 LAST LOCATION PC618_P0_2
J 0
(1925 2375);
DISPLAY 1.021277 (1925 2375);
PAINT AQUA (1925 2375);
DISPLAY INVISIBLE (1925 2375);
FORCEPROP 0 LAST $SEC 1
J 0
(1925 2375);
DISPLAY 0.680851 (1925 2375);
PAINT MONO (1925 2375);
DISPLAY INVISIBLE (1925 2375);
FORCEPROP 0 LAST CDS_SEC 1
J 0
(1925 2375);
DISPLAY 1.021277 (1925 2375);
DISPLAY INVISIBLE (1925 2375);
FORCEADD UNIVERSAL_GND..1
(-4725 4525);
FORCEPROP 3 LASTPIN (-4725 4575) SIG_NAME GND\g
J 0
(-4715 4585);
DISPLAY 0.659574 (-4715 4585);
PAINT MONO (-4715 4585);
DISPLAY INVISIBLE (-4715 4585);
FORCEPROP 1 LAST HDL_POWER GND
J 1
(-4700 4450);
DISPLAY 0.872340 (-4700 4450);
PAINT GREEN (-4700 4450);
DISPLAY INVISIBLE (-4700 4450);
FORCEPROP 2 LAST CDS_LIB logical_power
J 0
(-4725 4525);
PAINT MONO (-4725 4525);
DISPLAY INVISIBLE (-4725 4525);
FORCEPROP 1 LAST PATH I6
J 0
(-4650 4525);
DISPLAY 0.872340 (-4650 4525);
PAINT AQUA (-4650 4525);
DISPLAY INVISIBLE (-4650 4525);
FORCEADD Q_RES..2
(2300 2200);
FORCEPROP 1 LAST PART_NUMBER CS14992FB06
J 0
(2340 2075);
DISPLAY 0.617021 (2340 2075);
PAINT BLUE (2340 2075);
DISPLAY INVISIBLE (2340 2075);
FORCEPROP 1 LAST MATERIAL CHIP
J 0
(2340 2125);
DISPLAY 0.617021 (2340 2125);
PAINT SKYBLUE (2340 2125);
FORCEPROP 1 LAST VALUE 499
J 0
(2345 2275);
DISPLAY 0.617021 (2345 2275);
PAINT SKYBLUE (2345 2275);
FORCEPROP 1 LAST PACK_TYPE 0402LF
J 0
(2340 2025);
DISPLAY 0.617021 (2340 2025);
PAINT SKYBLUE (2340 2025);
FORCEPROP 1 LAST TOLERANCE 1%
J 0
(2345 2225);
DISPLAY 0.617021 (2345 2225);
PAINT SKYBLUE (2345 2225);
FORCEPROP 1 LAST WATTAGE 1/16W
J 0
(2340 2175);
DISPLAY 0.617021 (2340 2175);
PAINT SKYBLUE (2340 2175);
FORCEPROP 1 LAST LOCATION PR4265
J 0
(2345 2325);
DISPLAY 0.617021 (2345 2325);
PAINT AQUA (2345 2325);
FORCEPROP 1 LASTPIN (2300 2300) $PN 1
J 0
(2305 2262);
DISPLAY 0.787234 (2305 2262);
PAINT MONO (2305 2262);
FORCEPROP 1 LASTPIN (2300 2100) $PN 2
J 0
(2305 2110);
DISPLAY 0.787234 (2305 2110);
PAINT MONO (2305 2110);
FORCEPROP 2 LAST CDS_LIB pure_quanta
J 0
(2300 2200);
DISPLAY INVISIBLE (2300 2200);
FORCEPROP 2 LAST BOM_COST VR_PCH
J 0
(2350 2375);
DISPLAY 0.680851 (2350 2375);
DISPLAY INVISIBLE (2350 2375);
FORCEPROP 1 LAST PATH I60
J 0
(2350 2375);
DISPLAY 0.978723 (2350 2375);
PAINT WHITE (2350 2375);
DISPLAY INVISIBLE (2350 2375);
FORCEPROP 0 LAST $SEC 1
J 0
(2350 2375);
DISPLAY 0.680851 (2350 2375);
PAINT MONO (2350 2375);
DISPLAY INVISIBLE (2350 2375);
FORCEPROP 0 LAST CDS_SEC 1
J 0
(2350 2375);
DISPLAY 1.021277 (2350 2375);
DISPLAY INVISIBLE (2350 2375);
FORCEADD UNIVERSAL_GND..1
(2700 1775);
FORCEPROP 3 LASTPIN (2700 1825) SIG_NAME GND\g
J 0
(2710 1835);
DISPLAY 0.659574 (2710 1835);
PAINT MONO (2710 1835);
DISPLAY INVISIBLE (2710 1835);
FORCEPROP 1 LAST HDL_POWER GND
J 1
(2725 1700);
DISPLAY 0.872340 (2725 1700);
PAINT GREEN (2725 1700);
DISPLAY INVISIBLE (2725 1700);
FORCEPROP 2 LAST CDS_LIB logical_power
J 0
(2700 1775);
PAINT MONO (2700 1775);
DISPLAY INVISIBLE (2700 1775);
FORCEPROP 1 LAST PATH I61
J 0
(2775 1775);
DISPLAY 0.872340 (2775 1775);
PAINT AQUA (2775 1775);
DISPLAY INVISIBLE (2775 1775);
FORCEADD Q_CAPP..1
(2225 3325);
FORCEPROP 1 LAST PART_NUMBER CC7560JMD16
J 0
(2275 3175);
DISPLAY 0.617021 (2275 3175);
PAINT BLUE (2275 3175);
DISPLAY INVISIBLE (2275 3175);
FORCEPROP 1 LAST MATERIAL OSCON
J 0
(2275 3275);
DISPLAY 0.617021 (2275 3275);
PAINT RED (2275 3275);
FORCEPROP 1 LAST VOLTAGE 2.5V
J 0
(2275 3325);
DISPLAY 0.617021 (2275 3325);
PAINT SKYBLUE (2275 3325);
FORCEPROP 1 LAST PACK_TYPE THLF
J 0
(2275 3225);
DISPLAY 0.617021 (2275 3225);
PAINT SKYBLUE (2275 3225);
FORCEPROP 1 LAST VALUE 560UF
J 0
(2275 3425);
DISPLAY 0.617021 (2275 3425);
PAINT SKYBLUE (2275 3425);
FORCEPROP 1 LAST TOLERANCE 20%
J 0
(2275 3375);
DISPLAY 0.617021 (2275 3375);
PAINT SKYBLUE (2275 3375);
FORCEPROP 1 LAST LOCATION PC621
J 0
(2275 3475);
DISPLAY 0.617021 (2275 3475);
PAINT AQUA (2275 3475);
FORCEPROP 1 LASTPIN (2225 3425) $PN 1
J 0
(2235 3410);
DISPLAY 0.617021 (2235 3410);
PAINT MONO (2235 3410);
FORCEPROP 1 LASTPIN (2225 3225) $PN 2
J 0
(2235 3210);
DISPLAY 0.617021 (2235 3210);
PAINT MONO (2235 3210);
FORCEPROP 2 LAST CDS_LIB pure_quanta
J 0
(2225 3325);
DISPLAY INVISIBLE (2225 3325);
FORCEPROP 1 LAST PATH I62
J 0
(2275 3475);
DISPLAY 0.978723 (2275 3475);
DISPLAY INVISIBLE (2275 3475);
FORCEPROP 1 LAST LOCATION PC621
J 0
(2275 3525);
DISPLAY 1.021277 (2275 3525);
PAINT AQUA (2275 3525);
DISPLAY INVISIBLE (2275 3525);
FORCEPROP 0 LAST $SEC 1
J 0
(2275 3525);
DISPLAY 0.680851 (2275 3525);
PAINT MONO (2275 3525);
DISPLAY INVISIBLE (2275 3525);
FORCEPROP 0 LAST CDS_SEC 1
J 0
(2275 3525);
DISPLAY 1.021277 (2275 3525);
DISPLAY INVISIBLE (2275 3525);
FORCEADD Q_CAPP..1
(2725 3325);
FORCEPROP 1 LAST PART_NUMBER CH733LY8802
J 0
(2775 3175);
DISPLAY 0.617021 (2775 3175);
PAINT BLUE (2775 3175);
DISPLAY INVISIBLE (2775 3175);
FORCEPROP 1 LAST VOLTAGE 2.5V
J 0
(2775 3325);
DISPLAY 0.617021 (2775 3325);
PAINT SKYBLUE (2775 3325);
FORCEPROP 1 LAST MATERIAL SPCAP
J 0
(2775 3275);
DISPLAY 0.617021 (2775 3275);
PAINT SKYBLUE (2775 3275);
FORCEPROP 1 LAST PACK_TYPE SMLF
J 0
(2775 3225);
DISPLAY 0.617021 (2775 3225);
PAINT SKYBLUE (2775 3225);
FORCEPROP 1 LAST VALUE 330UF
J 0
(2775 3425);
DISPLAY 0.617021 (2775 3425);
PAINT SKYBLUE (2775 3425);
FORCEPROP 1 LAST TOLERANCE +10/-35%
J 0
(2775 3375);
DISPLAY 0.617021 (2775 3375);
PAINT SKYBLUE (2775 3375);
FORCEPROP 1 LAST LOCATION PC623
J 0
(2775 3475);
DISPLAY 0.617021 (2775 3475);
PAINT AQUA (2775 3475);
FORCEPROP 1 LASTPIN (2725 3425) $PN 1
J 0
(2735 3410);
DISPLAY 0.617021 (2735 3410);
PAINT MONO (2735 3410);
FORCEPROP 1 LASTPIN (2725 3225) $PN 2
J 0
(2735 3210);
DISPLAY 0.617021 (2735 3210);
PAINT MONO (2735 3210);
FORCEPROP 2 LAST CDS_LIB pure_quanta
J 0
(2725 3325);
DISPLAY INVISIBLE (2725 3325);
FORCEPROP 1 LAST PATH I63
J 0
(2775 3475);
DISPLAY 0.978723 (2775 3475);
DISPLAY INVISIBLE (2775 3475);
FORCEPROP 1 LAST LOCATION PC623
J 0
(2775 3525);
DISPLAY 1.021277 (2775 3525);
PAINT AQUA (2775 3525);
DISPLAY INVISIBLE (2775 3525);
FORCEPROP 0 LAST $SEC 1
J 0
(2775 3525);
DISPLAY 0.680851 (2775 3525);
PAINT MONO (2775 3525);
DISPLAY INVISIBLE (2775 3525);
FORCEPROP 0 LAST CDS_SEC 1
J 0
(2775 3525);
DISPLAY 1.021277 (2775 3525);
DISPLAY INVISIBLE (2775 3525);
FORCEADD UNIVERSAL_GND..1
(2175 4625);
FORCEPROP 3 LASTPIN (2175 4675) SIG_NAME GND\g
J 0
(2185 4685);
DISPLAY 0.659574 (2185 4685);
PAINT MONO (2185 4685);
DISPLAY INVISIBLE (2185 4685);
FORCEPROP 1 LAST HDL_POWER GND
J 1
(2200 4550);
DISPLAY 0.872340 (2200 4550);
PAINT GREEN (2200 4550);
DISPLAY INVISIBLE (2200 4550);
FORCEPROP 2 LAST CDS_LIB logical_power
J 0
(2175 4625);
PAINT MONO (2175 4625);
DISPLAY INVISIBLE (2175 4625);
FORCEPROP 1 LAST PATH I64
J 0
(2250 4625);
DISPLAY 0.872340 (2250 4625);
PAINT AQUA (2250 4625);
DISPLAY INVISIBLE (2250 4625);
FORCEADD VCC15..1
(2700 2625);
FORCEPROP 3 LASTPIN (2700 2575) SIG_NAME PVCCFA_EHV_FIVRA_CPU0\g
J 0
(2710 2585);
DISPLAY 0.659574 (2710 2585);
PAINT MONO (2710 2585);
DISPLAY INVISIBLE (2710 2585);
FORCEPROP 1 LAST HDL_POWER PVCCFA_EHV_FIVRA_CPU0
J 1
(2700 2675);
DISPLAY 0.617021 (2700 2675);
PAINT GREEN (2700 2675);
FORCEPROP 2 LAST CDS_LIB logical_power
J 0
(2700 2625);
DISPLAY INVISIBLE (2700 2625);
FORCEPROP 1 LAST PATH I65
J 0
(2750 2650);
DISPLAY 0.872340 (2750 2650);
PAINT AQUA (2750 2650);
DISPLAY INVISIBLE (2750 2650);
FORCEADD UNIVERSAL_GND..1
(3175 2975);
FORCEPROP 3 LASTPIN (3175 3025) SIG_NAME GND\g
J 0
(3185 3035);
DISPLAY 0.659574 (3185 3035);
PAINT MONO (3185 3035);
DISPLAY INVISIBLE (3185 3035);
FORCEPROP 1 LAST HDL_POWER GND
J 1
(3200 2900);
DISPLAY 0.872340 (3200 2900);
PAINT GREEN (3200 2900);
DISPLAY INVISIBLE (3200 2900);
FORCEPROP 2 LAST CDS_LIB logical_power
J 0
(3175 2975);
PAINT MONO (3175 2975);
DISPLAY INVISIBLE (3175 2975);
FORCEPROP 1 LAST PATH I66
J 0
(3250 2975);
DISPLAY 0.872340 (3250 2975);
PAINT AQUA (3250 2975);
DISPLAY INVISIBLE (3250 2975);
FORCEADD Q_CAPP..1
(3175 3325);
FORCEPROP 1 LAST PART_NUMBER CH733LY8802
J 0
(3250 3175);
DISPLAY 0.617021 (3250 3175);
PAINT BLUE (3250 3175);
DISPLAY INVISIBLE (3250 3175);
FORCEPROP 1 LAST MATERIAL SPCAP
J 0
(3250 3275);
DISPLAY 0.617021 (3250 3275);
PAINT RED (3250 3275);
FORCEPROP 1 LAST TOLERANCE +10/-35%
J 0
(3250 3375);
DISPLAY 0.617021 (3250 3375);
PAINT SKYBLUE (3250 3375);
FORCEPROP 1 LAST PACK_TYPE SMLF
J 0
(3250 3225);
DISPLAY 0.617021 (3250 3225);
PAINT SKYBLUE (3250 3225);
FORCEPROP 1 LAST VOLTAGE 2.5V
J 0
(3250 3325);
DISPLAY 0.617021 (3250 3325);
PAINT SKYBLUE (3250 3325);
FORCEPROP 1 LAST VALUE 330UF
J 0
(3250 3425);
DISPLAY 0.617021 (3250 3425);
PAINT SKYBLUE (3250 3425);
FORCEPROP 1 LAST LOCATION PC2645
J 0
(3250 3475);
DISPLAY 0.617021 (3250 3475);
PAINT AQUA (3250 3475);
FORCEPROP 1 LASTPIN (3175 3425) $PN 1
J 0
(3185 3410);
DISPLAY 0.617021 (3185 3410);
PAINT MONO (3185 3410);
FORCEPROP 1 LASTPIN (3175 3225) $PN 2
J 0
(3185 3210);
DISPLAY 0.617021 (3185 3210);
PAINT MONO (3185 3210);
FORCEPROP 2 LAST CDS_LIB pure_quanta
J 0
(3175 3325);
DISPLAY INVISIBLE (3175 3325);
FORCEPROP 1 LAST PATH I67
J 0
(3225 3475);
DISPLAY 0.978723 (3225 3475);
DISPLAY INVISIBLE (3225 3475);
FORCEPROP 2 LAST $SEC 1
J 0
(3225 3525);
DISPLAY 0.680851 (3225 3525);
PAINT MONO (3225 3525);
DISPLAY INVISIBLE (3225 3525);
FORCEPROP 2 LAST CDS_SEC 1
J 0
(3225 3525);
DISPLAY 1.021277 (3225 3525);
DISPLAY INVISIBLE (3225 3525);
FORCEADD VCC15..1
(3175 3650);
FORCEPROP 3 LASTPIN (3175 3600) SIG_NAME PVCCFA_EHV_FIVRA_CPU0\g
J 0
(3185 3610);
DISPLAY 0.659574 (3185 3610);
PAINT MONO (3185 3610);
DISPLAY INVISIBLE (3185 3610);
FORCEPROP 1 LAST HDL_POWER PVCCFA_EHV_FIVRA_CPU0
J 1
(3175 3700);
DISPLAY 0.617021 (3175 3700);
PAINT GREEN (3175 3700);
FORCEPROP 2 LAST CDS_LIB logical_power
J 0
(3175 3650);
DISPLAY INVISIBLE (3175 3650);
FORCEPROP 1 LAST PATH I68
J 0
(3225 3675);
DISPLAY 0.872340 (3225 3675);
PAINT AQUA (3225 3675);
DISPLAY INVISIBLE (3225 3675);
FORCEADD Q_RES..1
(-25 4950);
FORCEPROP 1 LAST PART_NUMBER CS00002JB13
J 0
(-125 4900);
DISPLAY 0.617021 (-125 4900);
PAINT BLUE (-125 4900);
DISPLAY INVISIBLE (-125 4900);
FORCEPROP 1 LAST WATTAGE 1/16W
J 2
(275 4850);
DISPLAY 0.489362 (275 4850);
PAINT SKYBLUE (275 4850);
FORCEPROP 1 LAST MATERIAL CHIP
J 0
(-125 4850);
DISPLAY 0.489362 (-125 4850);
PAINT SKYBLUE (-125 4850);
FORCEPROP 1 LAST PACK_TYPE 0402LF
J 0
(0 4850);
DISPLAY 0.489362 (0 4850);
PAINT SKYBLUE (0 4850);
FORCEPROP 1 LAST VALUE 0
J 2
(125 4950);
DISPLAY 0.617021 (125 4950);
PAINT SKYBLUE (125 4950);
FORCEPROP 1 LAST TOLERANCE 5%
J 0
(150 4950);
DISPLAY 0.617021 (150 4950);
PAINT SKYBLUE (150 4950);
FORCEPROP 1 LAST LOCATION PR1322
J 0
(-275 4950);
DISPLAY 0.617021 (-275 4950);
PAINT AQUA (-275 4950);
FORCEPROP 1 LASTPIN (-125 4950) $PN 1
J 0
(-113 4962);
DISPLAY 0.617021 (-113 4962);
FORCEPROP 1 LASTPIN (75 4950) $PN 2
J 0
(37 4962);
DISPLAY 0.617021 (37 4962);
FORCEPROP 2 LAST CDS_LIB pure_quanta
J 0
(-25 4950);
PAINT MONO (-25 4950);
DISPLAY INVISIBLE (-25 4950);
FORCEPROP 1 LAST PATH I69
J 0
(-75 5100);
DISPLAY 0.978723 (-75 5100);
PAINT WHITE (-75 5100);
DISPLAY INVISIBLE (-75 5100);
FORCEPROP 2 LAST $SEC 1
J 0
(-75 5150);
DISPLAY 0.680851 (-75 5150);
PAINT MONO (-75 5150);
DISPLAY INVISIBLE (-75 5150);
FORCEPROP 2 LAST CDS_SEC 1
J 0
(-75 5150);
DISPLAY 1.021277 (-75 5150);
DISPLAY INVISIBLE (-75 5150);
FORCEADD UNIVERSAL_GND..1
(-4800 4925);
FORCEPROP 3 LASTPIN (-4800 4975) SIG_NAME GND\g
J 0
(-4790 4985);
DISPLAY 0.659574 (-4790 4985);
PAINT MONO (-4790 4985);
DISPLAY INVISIBLE (-4790 4985);
FORCEPROP 1 LAST HDL_POWER GND
J 1
(-4775 4850);
DISPLAY 0.872340 (-4775 4850);
PAINT GREEN (-4775 4850);
DISPLAY INVISIBLE (-4775 4850);
FORCEPROP 2 LAST CDS_LIB logical_power
J 0
(-4800 4925);
PAINT MONO (-4800 4925);
DISPLAY INVISIBLE (-4800 4925);
FORCEPROP 1 LAST PATH I7
J 0
(-4725 4925);
DISPLAY 0.872340 (-4725 4925);
PAINT AQUA (-4725 4925);
DISPLAY INVISIBLE (-4725 4925);
FORCEADD Q_INDUCTOR..1
(-25 5225);
FORCEPROP 1 LAST PART_NUMBER CV+13^0KZ11
J 0
(-150 5335);
DISPLAY 0.617021 (-150 5335);
PAINT BLUE (-150 5335);
DISPLAY INVISIBLE (-150 5335);
FORCEPROP 2 LAST PACK_TYPE SMLF
J 0
(-150 5425);
DISPLAY 0.617021 (-150 5425);
PAINT SKYBLUE (-150 5425);
FORCEPROP 2 LAST VALUE 130NH/106A
J 0
(-150 5475);
DISPLAY 0.617021 (-150 5475);
PAINT SKYBLUE (-150 5475);
FORCEPROP 1 LAST MATERIAL IND
J 0
(-150 5280);
DISPLAY 0.617021 (-150 5280);
PAINT SKYBLUE (-150 5280);
FORCEPROP 1 LAST LOCATION PL33
J 0
(-150 5385);
DISPLAY 0.617021 (-150 5385);
PAINT AQUA (-150 5385);
FORCEPROP 0 LASTPIN (-125 5200) $PN 1
J 2
(-135 5210);
DISPLAY 0.617021 (-135 5210);
PAINT MONO (-135 5210);
FORCEPROP 0 LASTPIN (75 5200) $PN 2
J 0
(85 5210);
DISPLAY 0.617021 (85 5210);
PAINT MONO (85 5210);
FORCEPROP 2 LAST CDS_LIB pure_quanta
J 0
(-25 5225);
DISPLAY INVISIBLE (-25 5225);
FORCEPROP 1 LAST NEEDS_NO_SIZE TRUE
J 0
(-25 5225);
DISPLAY 0.468085 (-25 5225);
PAINT GREEN (-25 5225);
DISPLAY INVISIBLE (-25 5225);
FORCEPROP 1 LAST PATH I70
J 0
(50 5280);
DISPLAY 0.723404 (50 5280);
PAINT GREEN (50 5280);
DISPLAY INVISIBLE (50 5280);
FORCEPROP 0 LAST $SEC 1
J 0
(-150 5525);
DISPLAY 0.680851 (-150 5525);
PAINT MONO (-150 5525);
DISPLAY INVISIBLE (-150 5525);
FORCEPROP 0 LAST CDS_SEC 1
J 0
(-150 5525);
DISPLAY 1.021277 (-150 5525);
DISPLAY INVISIBLE (-150 5525);
FORCEADD Q_CAP..1
R 2
(-300 5475);
FORCEPROP 1 LAST PART_NUMBER CH4106K1B01
J 2
(-350 5400);
DISPLAY 0.617021 (-350 5400);
PAINT BLUE (-350 5400);
DISPLAY INVISIBLE (-350 5400);
FORCEPROP 1 LAST PACK_TYPE C0402
J 2
(-350 5375);
DISPLAY 0.617021 (-350 5375);
PAINT SKYBLUE (-350 5375);
FORCEPROP 1 LAST TOLERANCE 10%
J 2
(-350 5450);
DISPLAY 0.617021 (-350 5450);
PAINT SKYBLUE (-350 5450);
FORCEPROP 1 LAST MATERIAL X7R
J 2
(-350 5425);
DISPLAY 0.617021 (-350 5425);
PAINT SKYBLUE (-350 5425);
FORCEPROP 1 LAST VALUE 100NF
J 2
(-350 5500);
DISPLAY 0.617021 (-350 5500);
PAINT SKYBLUE (-350 5500);
FORCEPROP 1 LAST VOLTAGE 50V
J 2
(-350 5475);
DISPLAY 0.617021 (-350 5475);
PAINT SKYBLUE (-350 5475);
FORCEPROP 1 LAST LOCATION PC606
J 2
(-350 5550);
DISPLAY 0.617021 (-350 5550);
PAINT AQUA (-350 5550);
FORCEPROP 1 LASTPIN (-300 5575) $PN 1
J 2
(-310 5555);
DISPLAY 0.617021 (-310 5555);
FORCEPROP 1 LASTPIN (-300 5375) $PN 2
J 2
(-310 5355);
DISPLAY 0.617021 (-310 5355);
FORCEPROP 2 LAST CDS_LIB pure_quanta
J 2
(-300 5475);
PAINT MONO (-300 5475);
DISPLAY INVISIBLE (-300 5475);
FORCEPROP 1 LAST PATH I71
J 2
(-350 5625);
DISPLAY 0.978723 (-350 5625);
PAINT WHITE (-350 5625);
DISPLAY INVISIBLE (-350 5625);
FORCEPROP 2 LAST $SEC 1
J 0
(-350 5675);
DISPLAY 0.680851 (-350 5675);
PAINT MONO (-350 5675);
DISPLAY INVISIBLE (-350 5675);
FORCEPROP 2 LAST CDS_SEC 1
J 0
(-350 5675);
DISPLAY 1.021277 (-350 5675);
DISPLAY INVISIBLE (-350 5675);
FORCEADD UNIVERSAL_GND..1
(-125 5725);
FORCEPROP 3 LASTPIN (-125 5775) SIG_NAME GND\g
J 0
(-115 5785);
DISPLAY 0.659574 (-115 5785);
PAINT MONO (-115 5785);
DISPLAY INVISIBLE (-115 5785);
FORCEPROP 1 LAST HDL_POWER GND
J 1
(-100 5650);
DISPLAY 0.872340 (-100 5650);
PAINT GREEN (-100 5650);
DISPLAY INVISIBLE (-100 5650);
FORCEPROP 2 LAST CDS_LIB logical_power
J 0
(-125 5725);
PAINT MONO (-125 5725);
DISPLAY INVISIBLE (-125 5725);
FORCEPROP 1 LAST PATH I72
J 0
(-50 5725);
DISPLAY 0.872340 (-50 5725);
PAINT AQUA (-50 5725);
DISPLAY INVISIBLE (-50 5725);
FORCEADD Q_CAP..1
(-300 6125);
FORCEPROP 1 LAST PART_NUMBER CH6223MEA01
J 0
(-250 5975);
DISPLAY 0.617021 (-250 5975);
PAINT BLUE (-250 5975);
DISPLAY INVISIBLE (-250 5975);
FORCEPROP 1 LAST TOLERANCE 20%
J 0
(-250 6075);
DISPLAY 0.617021 (-250 6075);
PAINT SKYBLUE (-250 6075);
FORCEPROP 1 LAST PACK_TYPE C0805
J 0
(-250 5925);
DISPLAY 0.617021 (-250 5925);
PAINT SKYBLUE (-250 5925);
FORCEPROP 1 LAST VOLTAGE 16V
J 0
(-250 6125);
DISPLAY 0.617021 (-250 6125);
PAINT SKYBLUE (-250 6125);
FORCEPROP 1 LAST VALUE 22UF
J 0
(-250 6175);
DISPLAY 0.617021 (-250 6175);
PAINT SKYBLUE (-250 6175);
FORCEPROP 1 LAST MATERIAL X6S
J 0
(-250 6025);
DISPLAY 0.617021 (-250 6025);
PAINT SKYBLUE (-250 6025);
FORCEPROP 1 LAST LOCATION PC720_P0_1
J 0
(-250 6225);
DISPLAY 0.617021 (-250 6225);
PAINT AQUA (-250 6225);
FORCEPROP 1 LASTPIN (-300 6225) $PN 1
J 0
(-290 6205);
DISPLAY 0.787234 (-290 6205);
PAINT MONO (-290 6205);
FORCEPROP 1 LASTPIN (-300 6025) $PN 2
J 0
(-290 6005);
DISPLAY 0.787234 (-290 6005);
PAINT MONO (-290 6005);
FORCEPROP 2 LAST CDS_LIB pure_quanta
J 0
(-300 6125);
DISPLAY INVISIBLE (-300 6125);
FORCEPROP 1 LAST PATH I73
J 0
(-250 6275);
DISPLAY 0.978723 (-250 6275);
PAINT WHITE (-250 6275);
DISPLAY INVISIBLE (-250 6275);
FORCEPROP 0 LAST $SEC 1
J 0
(-250 6275);
DISPLAY 0.680851 (-250 6275);
PAINT MONO (-250 6275);
DISPLAY INVISIBLE (-250 6275);
FORCEPROP 0 LAST CDS_SEC 1
J 0
(-250 6275);
DISPLAY 1.021277 (-250 6275);
DISPLAY INVISIBLE (-250 6275);
FORCEADD VCC15..1
(-125 6475);
FORCEPROP 3 LASTPIN (-125 6425) SIG_NAME SW_P12V_PVCCFA_EHV_FIVRA_CPU0_R\g
J 0
(-115 6435);
DISPLAY 0.659574 (-115 6435);
PAINT MONO (-115 6435);
DISPLAY INVISIBLE (-115 6435);
FORCEPROP 1 LAST HDL_POWER SW_P12V_PVCCFA_EHV_FIVRA_CPU0_R
J 1
(-75 6525);
DISPLAY 0.617021 (-75 6525);
PAINT GREEN (-75 6525);
FORCEPROP 2 LAST CDS_LIB logical_power
J 0
(-125 6475);
DISPLAY INVISIBLE (-125 6475);
FORCEPROP 1 LAST PATH I74
J 0
(-75 6500);
DISPLAY 0.872340 (-75 6500);
PAINT AQUA (-75 6500);
DISPLAY INVISIBLE (-75 6500);
FORCEADD Q_CAP..1
(950 5000);
FORCEPROP 1 LAST PART_NUMBER CH4106K1B01
J 0
(1000 4825);
DISPLAY 0.617021 (1000 4825);
PAINT BLUE (1000 4825);
DISPLAY INVISIBLE (1000 4825);
FORCEPROP 1 LAST VOLTAGE 50V
J 0
(1000 5025);
DISPLAY 0.617021 (1000 5025);
PAINT SKYBLUE (1000 5025);
FORCEPROP 1 LAST TOLERANCE 10%
J 0
(1000 4975);
DISPLAY 0.617021 (1000 4975);
PAINT SKYBLUE (1000 4975);
FORCEPROP 1 LAST MATERIAL X7R
J 0
(1000 4925);
DISPLAY 0.617021 (1000 4925);
PAINT SKYBLUE (1000 4925);
FORCEPROP 1 LAST PACK_TYPE C0402
J 0
(1000 4875);
DISPLAY 0.617021 (1000 4875);
PAINT SKYBLUE (1000 4875);
FORCEPROP 1 LAST VALUE 100NF
J 0
(1000 5075);
DISPLAY 0.617021 (1000 5075);
PAINT SKYBLUE (1000 5075);
FORCEPROP 1 LAST LOCATION PC612_P0_1
J 0
(1000 5125);
DISPLAY 0.617021 (1000 5125);
PAINT AQUA (1000 5125);
FORCEPROP 1 LASTPIN (950 5100) $PN 1
J 0
(960 5080);
DISPLAY 0.617021 (960 5080);
PAINT MONO (960 5080);
FORCEPROP 1 LASTPIN (950 4900) $PN 2
J 0
(960 4880);
DISPLAY 0.617021 (960 4880);
PAINT MONO (960 4880);
FORCEPROP 2 LAST CDS_LIB pure_quanta
J 0
(950 5000);
DISPLAY INVISIBLE (950 5000);
FORCEPROP 1 LAST PATH I75
J 0
(1000 5150);
DISPLAY 0.978723 (1000 5150);
PAINT WHITE (1000 5150);
DISPLAY INVISIBLE (1000 5150);
FORCEPROP 1 LAST LOCATION PC612_P0_1
J 0
(1000 5175);
DISPLAY 1.021277 (1000 5175);
PAINT AQUA (1000 5175);
DISPLAY INVISIBLE (1000 5175);
FORCEPROP 0 LAST $SEC 1
J 0
(1000 5175);
DISPLAY 0.680851 (1000 5175);
PAINT MONO (1000 5175);
DISPLAY INVISIBLE (1000 5175);
FORCEPROP 0 LAST CDS_SEC 1
J 0
(1000 5175);
DISPLAY 1.021277 (1000 5175);
DISPLAY INVISIBLE (1000 5175);
FORCEADD GND..1
(1000 5625);
FORCEPROP 3 LASTPIN (1000 5675) SIG_NAME GND\g
J 0
(1010 5685);
DISPLAY 0.659574 (1010 5685);
PAINT MONO (1010 5685);
DISPLAY INVISIBLE (1010 5685);
FORCEPROP 1 LAST HDL_POWER GND
J 0
(1000 5775);
DISPLAY 0.872340 (1000 5775);
PAINT GREEN (1000 5775);
DISPLAY INVISIBLE (1000 5775);
FORCEPROP 2 LAST CDS_LIB logical_power
J 0
(1000 5625);
DISPLAY INVISIBLE (1000 5625);
FORCEPROP 1 LAST SIZE 1B
J 0
(1075 5575);
DISPLAY 0.872340 (1075 5575);
PAINT AQUA (1075 5575);
DISPLAY INVISIBLE (1075 5575);
FORCEPROP 1 LAST PATH I76
J 0
(1075 5625);
DISPLAY 0.872340 (1075 5625);
PAINT AQUA (1075 5625);
DISPLAY INVISIBLE (1075 5625);
FORCEADD Q_CAP..1
(1450 5000);
FORCEPROP 1 LAST PART_NUMBER CH622KMEA03
J 0
(1500 4825);
DISPLAY 0.489362 (1500 4825);
PAINT BLUE (1500 4825);
DISPLAY INVISIBLE (1500 4825);
FORCEPROP 1 LAST TOLERANCE 20%
J 0
(1500 4975);
DISPLAY 0.617021 (1500 4975);
PAINT SKYBLUE (1500 4975);
FORCEPROP 1 LAST PACK_TYPE C0805
J 0
(1500 4875);
DISPLAY 0.617021 (1500 4875);
PAINT SKYBLUE (1500 4875);
FORCEPROP 1 LAST MATERIAL X6S
J 0
(1500 4925);
DISPLAY 0.617021 (1500 4925);
PAINT SKYBLUE (1500 4925);
FORCEPROP 1 LAST VALUE 22UF
J 0
(1500 5075);
DISPLAY 0.617021 (1500 5075);
PAINT SKYBLUE (1500 5075);
FORCEPROP 1 LAST VOLTAGE 4V
J 0
(1500 5025);
DISPLAY 0.617021 (1500 5025);
PAINT SKYBLUE (1500 5025);
FORCEPROP 1 LAST LOCATION PC615_P0_1
J 0
(1500 5125);
DISPLAY 0.617021 (1500 5125);
PAINT AQUA (1500 5125);
FORCEPROP 1 LASTPIN (1450 5100) $PN 1
J 0
(1460 5080);
DISPLAY 0.617021 (1460 5080);
PAINT MONO (1460 5080);
FORCEPROP 1 LASTPIN (1450 4900) $PN 2
J 0
(1460 4880);
DISPLAY 0.617021 (1460 4880);
PAINT MONO (1460 4880);
FORCEPROP 2 LAST CDS_LIB pure_quanta
J 0
(1450 5000);
DISPLAY INVISIBLE (1450 5000);
FORCEPROP 1 LAST PATH I77
J 0
(1500 5150);
DISPLAY 0.978723 (1500 5150);
PAINT WHITE (1500 5150);
DISPLAY INVISIBLE (1500 5150);
FORCEPROP 1 LAST LOCATION PC615_P0_1
J 0
(1500 5175);
DISPLAY 1.021277 (1500 5175);
PAINT AQUA (1500 5175);
DISPLAY INVISIBLE (1500 5175);
FORCEPROP 0 LAST $SEC 1
J 0
(1500 5175);
DISPLAY 0.680851 (1500 5175);
PAINT MONO (1500 5175);
DISPLAY INVISIBLE (1500 5175);
FORCEPROP 0 LAST CDS_SEC 1
J 0
(1500 5175);
DISPLAY 1.021277 (1500 5175);
DISPLAY INVISIBLE (1500 5175);
FORCEADD Q_CAP..1
(1000 5875);
FORCEPROP 1 LAST PART_NUMBER CH4106K1B01
J 0
(1050 5725);
DISPLAY 0.787234 (1050 5725);
DISPLAY INVISIBLE (1050 5725);
FORCEPROP 1 LAST TOLERANCE 10%
J 0
(1050 5825);
DISPLAY 0.787234 (1050 5825);
FORCEPROP 1 LAST VALUE 100NF
J 0
(1050 5925);
DISPLAY 0.787234 (1050 5925);
FORCEPROP 1 LAST VOLTAGE 50V
J 0
(1050 5875);
DISPLAY 0.787234 (1050 5875);
FORCEPROP 1 LAST MATERIAL X7R
J 0
(1050 5775);
DISPLAY 0.787234 (1050 5775);
FORCEPROP 1 LAST PACK_TYPE C0402
J 0
(1050 5675);
DISPLAY 0.787234 (1050 5675);
FORCEPROP 1 LAST LOCATION PC1653
J 0
(1050 5975);
DISPLAY 0.787234 (1050 5975);
FORCEPROP 1 LASTPIN (1000 5975) $PN 1
J 0
(1010 5955);
DISPLAY 0.787234 (1010 5955);
PAINT MONO (1010 5955);
FORCEPROP 1 LASTPIN (1000 5775) $PN 2
J 0
(1010 5755);
DISPLAY 0.787234 (1010 5755);
PAINT MONO (1010 5755);
FORCEPROP 2 LAST CDS_LIB pure_quanta
J 0
(1000 5875);
DISPLAY INVISIBLE (1000 5875);
FORCEPROP 1 LAST PATH I78
J 0
(1050 6025);
DISPLAY 0.978723 (1050 6025);
PAINT WHITE (1050 6025);
DISPLAY INVISIBLE (1050 6025);
FORCEPROP 0 LAST $SEC 1
J 0
(1050 6025);
DISPLAY 0.680851 (1050 6025);
PAINT MONO (1050 6025);
DISPLAY INVISIBLE (1050 6025);
FORCEPROP 0 LAST CDS_SEC 1
J 0
(1050 6025);
DISPLAY 1.021277 (1050 6025);
DISPLAY INVISIBLE (1050 6025);
FORCEADD VCC15..1
(1000 6250);
FORCEPROP 3 LASTPIN (1000 6200) SIG_NAME P12V_AUX\g
J 0
(1010 6210);
DISPLAY 0.659574 (1010 6210);
PAINT MONO (1010 6210);
DISPLAY INVISIBLE (1010 6210);
FORCEPROP 1 LAST HDL_POWER P12V_AUX
J 1
(1000 6300);
DISPLAY 0.617021 (1000 6300);
PAINT GREEN (1000 6300);
FORCEPROP 2 LAST CDS_LIB logical_power
J 0
(1000 6250);
DISPLAY INVISIBLE (1000 6250);
FORCEPROP 1 LAST PATH I79
J 0
(1050 6275);
DISPLAY 0.872340 (1050 6275);
PAINT AQUA (1050 6275);
DISPLAY INVISIBLE (1050 6275);
FORCEADD Q_RES..2
R 2
(-4725 4750);
FORCEPROP 1 LAST PART_NUMBER CS28872FB01
J 2
(-4775 4625);
DISPLAY 0.617021 (-4775 4625);
PAINT BLUE (-4775 4625);
DISPLAY INVISIBLE (-4775 4625);
FORCEPROP 1 LAST VALUE 8.87K
J 2
(-4780 4825);
DISPLAY 0.617021 (-4780 4825);
PAINT SKYBLUE (-4780 4825);
FORCEPROP 1 LAST TOLERANCE 1%
J 2
(-4780 4775);
DISPLAY 0.617021 (-4780 4775);
PAINT SKYBLUE (-4780 4775);
FORCEPROP 1 LAST WATTAGE 1/16W
J 2
(-4775 4725);
DISPLAY 0.617021 (-4775 4725);
PAINT SKYBLUE (-4775 4725);
FORCEPROP 1 LAST PACK_TYPE 0402LF
J 2
(-4775 4575);
DISPLAY 0.617021 (-4775 4575);
PAINT SKYBLUE (-4775 4575);
FORCEPROP 1 LAST MATERIAL EMPTY
J 2
(-4775 4675);
DISPLAY 0.617021 (-4775 4675);
PAINT RED (-4775 4675);
FORCEPROP 1 LAST LOCATION PR354
J 2
(-4770 4875);
DISPLAY 0.617021 (-4770 4875);
PAINT AQUA (-4770 4875);
FORCEPROP 1 LASTPIN (-4725 4850) $PN 1
J 2
(-4730 4812);
DISPLAY 0.617021 (-4730 4812);
PAINT MONO (-4730 4812);
FORCEPROP 1 LASTPIN (-4725 4650) $PN 2
J 2
(-4730 4660);
DISPLAY 0.617021 (-4730 4660);
PAINT MONO (-4730 4660);
FORCEPROP 2 LAST CDS_LIB pure_quanta
J 2
(-4725 4750);
DISPLAY INVISIBLE (-4725 4750);
FORCEPROP 1 LAST PATH I8
J 2
(-4775 4925);
DISPLAY 0.978723 (-4775 4925);
PAINT WHITE (-4775 4925);
DISPLAY INVISIBLE (-4775 4925);
FORCEPROP 1 LAST LOCATION PR354
J 2
(-4775 4925);
DISPLAY 1.021277 (-4775 4925);
PAINT AQUA (-4775 4925);
DISPLAY INVISIBLE (-4775 4925);
FORCEPROP 0 LAST $SEC 1
J 2
(-4775 4925);
DISPLAY 0.680851 (-4775 4925);
PAINT MONO (-4775 4925);
DISPLAY INVISIBLE (-4775 4925);
FORCEPROP 0 LAST CDS_SEC 1
J 2
(-4775 4925);
DISPLAY 1.021277 (-4775 4925);
DISPLAY INVISIBLE (-4775 4925);
FORCEADD Q_INDUCTOR..1
(1425 6100);
FORCEPROP 1 LAST PART_NUMBER CV+10G0MZ04
J 0
(1325 5850);
DISPLAY 0.617021 (1325 5850);
PAINT BLUE (1325 5850);
DISPLAY INVISIBLE (1325 5850);
FORCEPROP 2 LAST PACK_TYPE SMLF
J 0
(1325 5950);
DISPLAY 0.617021 (1325 5950);
PAINT SKYBLUE (1325 5950);
FORCEPROP 1 LAST MATERIAL IND
J 0
(1325 5900);
DISPLAY 0.617021 (1325 5900);
PAINT SKYBLUE (1325 5900);
FORCEPROP 2 LAST VALUE 100NH/16A
J 0
(1325 6000);
DISPLAY 0.617021 (1325 6000);
PAINT SKYBLUE (1325 6000);
FORCEPROP 1 LAST LOCATION PL44
J 0
(1150 6085);
DISPLAY 0.617021 (1150 6085);
PAINT AQUA (1150 6085);
FORCEPROP 2 LASTPIN (1325 6075) $PN 1
J 2
(1315 6085);
DISPLAY 0.617021 (1315 6085);
FORCEPROP 2 LASTPIN (1525 6075) $PN 2
J 0
(1535 6085);
DISPLAY 0.617021 (1535 6085);
FORCEPROP 2 LAST CDS_LIB pure_quanta
J 0
(1425 6100);
PAINT MONO (1425 6100);
DISPLAY INVISIBLE (1425 6100);
FORCEPROP 1 LAST NEEDS_NO_SIZE TRUE
J 0
(1425 6100);
DISPLAY 0.468085 (1425 6100);
PAINT GREEN (1425 6100);
DISPLAY INVISIBLE (1425 6100);
FORCEPROP 1 LAST PATH I80
J 0
(1500 6155);
DISPLAY 0.723404 (1500 6155);
PAINT GREEN (1500 6155);
DISPLAY INVISIBLE (1500 6155);
FORCEPROP 2 LAST $SEC 1
J 0
(1500 6200);
DISPLAY 0.680851 (1500 6200);
PAINT MONO (1500 6200);
DISPLAY INVISIBLE (1500 6200);
FORCEPROP 2 LAST CDS_SEC 1
J 0
(1500 6200);
DISPLAY 1.021277 (1500 6200);
DISPLAY INVISIBLE (1500 6200);
FORCEADD Q_CAP..1
(1875 5000);
FORCEPROP 1 LAST PART_NUMBER CH622KMEA03
J 0
(1925 4825);
DISPLAY 0.489362 (1925 4825);
PAINT BLUE (1925 4825);
DISPLAY INVISIBLE (1925 4825);
FORCEPROP 1 LAST TOLERANCE 20%
J 0
(1925 4975);
DISPLAY 0.617021 (1925 4975);
PAINT SKYBLUE (1925 4975);
FORCEPROP 1 LAST PACK_TYPE C0805
J 0
(1925 4875);
DISPLAY 0.617021 (1925 4875);
PAINT SKYBLUE (1925 4875);
FORCEPROP 1 LAST VOLTAGE 4V
J 0
(1925 5025);
DISPLAY 0.617021 (1925 5025);
PAINT SKYBLUE (1925 5025);
FORCEPROP 1 LAST VALUE 22UF
J 0
(1925 5075);
DISPLAY 0.617021 (1925 5075);
PAINT SKYBLUE (1925 5075);
FORCEPROP 1 LAST MATERIAL X6S
J 0
(1925 4925);
DISPLAY 0.617021 (1925 4925);
PAINT SKYBLUE (1925 4925);
FORCEPROP 1 LAST LOCATION PC617_P0_1
J 0
(1925 5125);
DISPLAY 0.617021 (1925 5125);
PAINT AQUA (1925 5125);
FORCEPROP 1 LASTPIN (1875 5100) $PN 1
J 0
(1885 5080);
DISPLAY 0.617021 (1885 5080);
PAINT MONO (1885 5080);
FORCEPROP 1 LASTPIN (1875 4900) $PN 2
J 0
(1885 4880);
DISPLAY 0.617021 (1885 4880);
PAINT MONO (1885 4880);
FORCEPROP 2 LAST CDS_LIB pure_quanta
J 0
(1875 5000);
DISPLAY INVISIBLE (1875 5000);
FORCEPROP 1 LAST PATH I81
J 0
(1925 5150);
DISPLAY 0.978723 (1925 5150);
PAINT WHITE (1925 5150);
DISPLAY INVISIBLE (1925 5150);
FORCEPROP 1 LAST LOCATION PC617_P0_1
J 0
(1925 5175);
DISPLAY 1.021277 (1925 5175);
PAINT AQUA (1925 5175);
DISPLAY INVISIBLE (1925 5175);
FORCEPROP 0 LAST $SEC 1
J 0
(1925 5175);
DISPLAY 0.680851 (1925 5175);
PAINT MONO (1925 5175);
DISPLAY INVISIBLE (1925 5175);
FORCEPROP 0 LAST CDS_SEC 1
J 0
(1925 5175);
DISPLAY 1.021277 (1925 5175);
DISPLAY INVISIBLE (1925 5175);
FORCEADD VCC15..1
(2175 5400);
FORCEPROP 3 LASTPIN (2175 5350) SIG_NAME PVCCFA_EHV_FIVRA_CPU0\g
J 0
(2185 5360);
DISPLAY 0.659574 (2185 5360);
PAINT MONO (2185 5360);
DISPLAY INVISIBLE (2185 5360);
FORCEPROP 1 LAST HDL_POWER PVCCFA_EHV_FIVRA_CPU0
J 1
(2175 5450);
DISPLAY 0.617021 (2175 5450);
PAINT GREEN (2175 5450);
FORCEPROP 2 LAST CDS_LIB logical_power
J 0
(2175 5400);
DISPLAY INVISIBLE (2175 5400);
FORCEPROP 1 LAST PATH I82
J 0
(2225 5425);
DISPLAY 0.872340 (2225 5425);
PAINT AQUA (2225 5425);
DISPLAY INVISIBLE (2225 5425);
FORCEADD Q_CAP..1
(1775 5850);
FORCEPROP 1 LAST PART_NUMBER CH6223MEA01
J 0
(1825 5725);
DISPLAY 0.404255 (1825 5725);
DISPLAY INVISIBLE (1825 5725);
FORCEPROP 1 LAST TOLERANCE 20%
J 0
(1825 5825);
DISPLAY 0.510638 (1825 5825);
FORCEPROP 1 LAST VOLTAGE 16V
J 0
(1825 5875);
DISPLAY 0.510638 (1825 5875);
FORCEPROP 1 LAST MATERIAL X6S
J 0
(1825 5775);
DISPLAY 0.510638 (1825 5775);
FORCEPROP 1 LAST PACK_TYPE C0805
J 0
(1825 5675);
DISPLAY 0.510638 (1825 5675);
FORCEPROP 1 LAST VALUE 22UF
J 0
(1825 5925);
DISPLAY 0.510638 (1825 5925);
FORCEPROP 1 LAST LOCATION PC1669
J 0
(1825 5975);
DISPLAY 0.510638 (1825 5975);
FORCEPROP 1 LASTPIN (1775 5950) $PN 1
J 0
(1785 5930);
DISPLAY 0.787234 (1785 5930);
PAINT MONO (1785 5930);
FORCEPROP 1 LASTPIN (1775 5750) $PN 2
J 0
(1785 5730);
DISPLAY 0.787234 (1785 5730);
PAINT MONO (1785 5730);
FORCEPROP 2 LAST CDS_LIB pure_quanta
J 0
(1775 5850);
DISPLAY INVISIBLE (1775 5850);
FORCEPROP 1 LAST PATH I83
J 0
(1825 6000);
DISPLAY 0.978723 (1825 6000);
PAINT WHITE (1825 6000);
DISPLAY INVISIBLE (1825 6000);
FORCEPROP 0 LAST $SEC 1
J 0
(1825 6000);
DISPLAY 0.680851 (1825 6000);
PAINT MONO (1825 6000);
DISPLAY INVISIBLE (1825 6000);
FORCEPROP 0 LAST CDS_SEC 1
J 0
(1825 6000);
DISPLAY 1.021277 (1825 6000);
DISPLAY INVISIBLE (1825 6000);
FORCEADD Q_CAP..1
(2075 5850);
FORCEPROP 1 LAST PART_NUMBER CH6223MEA01
J 0
(2125 5725);
DISPLAY 0.404255 (2125 5725);
DISPLAY INVISIBLE (2125 5725);
FORCEPROP 1 LAST TOLERANCE 20%
J 0
(2125 5825);
DISPLAY 0.510638 (2125 5825);
FORCEPROP 1 LAST VALUE 22UF
J 0
(2125 5925);
DISPLAY 0.510638 (2125 5925);
FORCEPROP 1 LAST MATERIAL X6S
J 0
(2125 5775);
DISPLAY 0.510638 (2125 5775);
FORCEPROP 1 LAST PACK_TYPE C0805
J 0
(2125 5675);
DISPLAY 0.510638 (2125 5675);
FORCEPROP 1 LAST VOLTAGE 16V
J 0
(2125 5875);
DISPLAY 0.510638 (2125 5875);
FORCEPROP 1 LAST LOCATION PC1670
J 0
(2125 5975);
DISPLAY 0.510638 (2125 5975);
FORCEPROP 1 LASTPIN (2075 5950) $PN 1
J 0
(2085 5930);
DISPLAY 0.787234 (2085 5930);
PAINT MONO (2085 5930);
FORCEPROP 1 LASTPIN (2075 5750) $PN 2
J 0
(2085 5730);
DISPLAY 0.787234 (2085 5730);
PAINT MONO (2085 5730);
FORCEPROP 2 LAST CDS_LIB pure_quanta
J 0
(2075 5850);
DISPLAY INVISIBLE (2075 5850);
FORCEPROP 1 LAST PATH I84
J 0
(2125 6000);
DISPLAY 0.978723 (2125 6000);
PAINT WHITE (2125 6000);
DISPLAY INVISIBLE (2125 6000);
FORCEPROP 0 LAST $SEC 1
J 0
(2125 6000);
DISPLAY 0.680851 (2125 6000);
PAINT MONO (2125 6000);
DISPLAY INVISIBLE (2125 6000);
FORCEPROP 0 LAST CDS_SEC 1
J 0
(2125 6000);
DISPLAY 1.021277 (2125 6000);
DISPLAY INVISIBLE (2125 6000);
FORCEADD Q_CAP..1
(2350 5850);
FORCEPROP 1 LAST PART_NUMBER CH6223MEA01
J 0
(2400 5725);
DISPLAY 0.404255 (2400 5725);
DISPLAY INVISIBLE (2400 5725);
FORCEPROP 1 LAST TOLERANCE 20%
J 0
(2400 5825);
DISPLAY 0.510638 (2400 5825);
FORCEPROP 1 LAST MATERIAL X6S
J 0
(2400 5775);
DISPLAY 0.510638 (2400 5775);
FORCEPROP 1 LAST VALUE 22UF
J 0
(2400 5925);
DISPLAY 0.510638 (2400 5925);
FORCEPROP 1 LAST VOLTAGE 16V
J 0
(2400 5875);
DISPLAY 0.510638 (2400 5875);
FORCEPROP 1 LAST PACK_TYPE C0805
J 0
(2400 5675);
DISPLAY 0.510638 (2400 5675);
FORCEPROP 1 LAST LOCATION PC1671
J 0
(2400 5975);
DISPLAY 0.510638 (2400 5975);
FORCEPROP 1 LASTPIN (2350 5950) $PN 1
J 0
(2360 5930);
DISPLAY 0.787234 (2360 5930);
PAINT MONO (2360 5930);
FORCEPROP 1 LASTPIN (2350 5750) $PN 2
J 0
(2360 5730);
DISPLAY 0.787234 (2360 5730);
PAINT MONO (2360 5730);
FORCEPROP 2 LAST CDS_LIB pure_quanta
J 0
(2350 5850);
DISPLAY INVISIBLE (2350 5850);
FORCEPROP 1 LAST PATH I85
J 0
(2400 6000);
DISPLAY 0.978723 (2400 6000);
PAINT WHITE (2400 6000);
DISPLAY INVISIBLE (2400 6000);
FORCEPROP 0 LAST $SEC 1
J 0
(2400 6000);
DISPLAY 0.680851 (2400 6000);
PAINT MONO (2400 6000);
DISPLAY INVISIBLE (2400 6000);
FORCEPROP 0 LAST CDS_SEC 1
J 0
(2400 6000);
DISPLAY 1.021277 (2400 6000);
DISPLAY INVISIBLE (2400 6000);
FORCEADD Q_CAP..1
(2625 5850);
FORCEPROP 1 LAST PART_NUMBER CH6223MEA01
J 0
(2675 5725);
DISPLAY 0.404255 (2675 5725);
DISPLAY INVISIBLE (2675 5725);
FORCEPROP 1 LAST TOLERANCE 20%
J 0
(2675 5825);
DISPLAY 0.510638 (2675 5825);
FORCEPROP 1 LAST PACK_TYPE C0805
J 0
(2675 5675);
DISPLAY 0.510638 (2675 5675);
FORCEPROP 1 LAST MATERIAL X6S
J 0
(2675 5775);
DISPLAY 0.510638 (2675 5775);
FORCEPROP 1 LAST VOLTAGE 16V
J 0
(2675 5875);
DISPLAY 0.510638 (2675 5875);
FORCEPROP 1 LAST VALUE 22UF
J 0
(2675 5925);
DISPLAY 0.510638 (2675 5925);
FORCEPROP 1 LAST LOCATION PC1672
J 0
(2675 5975);
DISPLAY 0.510638 (2675 5975);
FORCEPROP 1 LASTPIN (2625 5950) $PN 1
J 0
(2635 5930);
DISPLAY 0.787234 (2635 5930);
PAINT MONO (2635 5930);
FORCEPROP 1 LASTPIN (2625 5750) $PN 2
J 0
(2635 5730);
DISPLAY 0.787234 (2635 5730);
PAINT MONO (2635 5730);
FORCEPROP 2 LAST CDS_LIB pure_quanta
J 0
(2625 5850);
DISPLAY INVISIBLE (2625 5850);
FORCEPROP 1 LAST PATH I86
J 0
(2675 6000);
DISPLAY 0.978723 (2675 6000);
PAINT WHITE (2675 6000);
DISPLAY INVISIBLE (2675 6000);
FORCEPROP 0 LAST $SEC 1
J 0
(2675 6000);
DISPLAY 0.680851 (2675 6000);
PAINT MONO (2675 6000);
DISPLAY INVISIBLE (2675 6000);
FORCEPROP 0 LAST CDS_SEC 1
J 0
(2675 6000);
DISPLAY 1.021277 (2675 6000);
DISPLAY INVISIBLE (2675 6000);
FORCEADD UNIVERSAL_GND..1
(2900 5575);
FORCEPROP 3 LASTPIN (2900 5625) SIG_NAME GND\g
J 0
(2910 5635);
DISPLAY 0.659574 (2910 5635);
PAINT MONO (2910 5635);
DISPLAY INVISIBLE (2910 5635);
FORCEPROP 1 LAST HDL_POWER GND
J 1
(2925 5500);
DISPLAY 0.872340 (2925 5500);
PAINT GREEN (2925 5500);
DISPLAY INVISIBLE (2925 5500);
FORCEPROP 2 LAST CDS_LIB logical_power
J 0
(2900 5575);
PAINT MONO (2900 5575);
DISPLAY INVISIBLE (2900 5575);
FORCEPROP 1 LAST PATH I87
J 0
(2975 5575);
DISPLAY 0.872340 (2975 5575);
PAINT AQUA (2975 5575);
DISPLAY INVISIBLE (2975 5575);
FORCEADD Q_CAPP..1
(2900 5850);
FORCEPROP 1 LAST PART_NUMBER CC72703MD38
J 0
(2950 5675);
DISPLAY 0.617021 (2950 5675);
PAINT BLUE (2950 5675);
DISPLAY INVISIBLE (2950 5675);
FORCEPROP 1 LAST PACK_TYPE THLF
J 0
(2950 5725);
DISPLAY 0.617021 (2950 5725);
PAINT SKYBLUE (2950 5725);
FORCEPROP 1 LAST TOLERANCE 20%
J 0
(2950 5875);
DISPLAY 0.617021 (2950 5875);
PAINT SKYBLUE (2950 5875);
FORCEPROP 1 LAST MATERIAL OSCON
J 0
(2950 5775);
DISPLAY 0.617021 (2950 5775);
PAINT SKYBLUE (2950 5775);
FORCEPROP 1 LAST VALUE 270UF
J 0
(2950 5925);
DISPLAY 0.617021 (2950 5925);
PAINT SKYBLUE (2950 5925);
FORCEPROP 1 LAST VOLTAGE 16V
J 0
(2950 5825);
DISPLAY 0.617021 (2950 5825);
PAINT SKYBLUE (2950 5825);
FORCEPROP 1 LAST LOCATION PC622
J 0
(2950 5975);
DISPLAY 0.617021 (2950 5975);
PAINT AQUA (2950 5975);
FORCEPROP 1 LASTPIN (2900 5950) $PN 1
J 0
(2910 5935);
DISPLAY 0.617021 (2910 5935);
PAINT MONO (2910 5935);
FORCEPROP 1 LASTPIN (2900 5750) $PN 2
J 0
(2910 5735);
DISPLAY 0.617021 (2910 5735);
PAINT MONO (2910 5735);
FORCEPROP 2 LAST CDS_LIB pure_quanta
J 0
(2900 5850);
DISPLAY INVISIBLE (2900 5850);
FORCEPROP 1 LAST PATH I88
J 0
(2950 6000);
DISPLAY 0.978723 (2950 6000);
DISPLAY INVISIBLE (2950 6000);
FORCEPROP 1 LAST LOCATION PC622
J 0
(2950 6025);
DISPLAY 1.021277 (2950 6025);
PAINT AQUA (2950 6025);
DISPLAY INVISIBLE (2950 6025);
FORCEPROP 0 LAST $SEC 1
J 0
(2950 6025);
DISPLAY 0.680851 (2950 6025);
PAINT MONO (2950 6025);
DISPLAY INVISIBLE (2950 6025);
FORCEPROP 0 LAST CDS_SEC 1
J 0
(2950 6025);
DISPLAY 1.021277 (2950 6025);
DISPLAY INVISIBLE (2950 6025);
FORCEADD VCC15..1
(3025 6225);
FORCEPROP 3 LASTPIN (3025 6175) SIG_NAME SW_P12V_PVCCFA_EHV_FIVRA_CPU0_L\g
J 0
(3035 6185);
DISPLAY 0.659574 (3035 6185);
PAINT MONO (3035 6185);
DISPLAY INVISIBLE (3035 6185);
FORCEPROP 1 LAST HDL_POWER SW_P12V_PVCCFA_EHV_FIVRA_CPU0_L
J 1
(3075 6275);
DISPLAY 0.617021 (3075 6275);
PAINT GREEN (3075 6275);
FORCEPROP 2 LAST CDS_LIB logical_power
J 0
(3025 6225);
DISPLAY INVISIBLE (3025 6225);
FORCEPROP 1 LAST PATH I89
J 0
(3075 6250);
DISPLAY 0.872340 (3075 6250);
PAINT AQUA (3075 6250);
DISPLAY INVISIBLE (3075 6250);
FORCEADD Q_RES..2
(-4825 6700);
FORCEPROP 1 LAST PART_NUMBER CS00002JB13
J 0
(-4785 6575);
DISPLAY 0.617021 (-4785 6575);
PAINT BLUE (-4785 6575);
DISPLAY INVISIBLE (-4785 6575);
FORCEPROP 1 LAST PACK_TYPE 0402LF
J 0
(-4785 6525);
DISPLAY 0.617021 (-4785 6525);
PAINT SKYBLUE (-4785 6525);
FORCEPROP 1 LAST VALUE 0
J 0
(-4780 6775);
DISPLAY 0.617021 (-4780 6775);
PAINT SKYBLUE (-4780 6775);
FORCEPROP 1 LAST TOLERANCE 5%
J 0
(-4780 6725);
DISPLAY 0.617021 (-4780 6725);
PAINT SKYBLUE (-4780 6725);
FORCEPROP 1 LAST MATERIAL CHIP
J 0
(-4785 6625);
DISPLAY 0.617021 (-4785 6625);
PAINT SKYBLUE (-4785 6625);
FORCEPROP 1 LAST WATTAGE 1/16W
J 0
(-4785 6675);
DISPLAY 0.617021 (-4785 6675);
PAINT SKYBLUE (-4785 6675);
FORCEPROP 1 LAST LOCATION PR444
J 0
(-4780 6825);
DISPLAY 0.617021 (-4780 6825);
PAINT AQUA (-4780 6825);
FORCEPROP 2 LAST CDS_LIB pure_quanta
J 0
(-4825 6700);
DISPLAY INVISIBLE (-4825 6700);
FORCEPROP 1 LAST PATH I9
J 0
(-4775 6875);
DISPLAY 0.978723 (-4775 6875);
PAINT WHITE (-4775 6875);
DISPLAY INVISIBLE (-4775 6875);
FORCEPROP 0 LAST $SEC 1
J 0
(-4775 6875);
DISPLAY INVISIBLE (-4775 6875);
FORCEPROP 0 LAST CDS_SEC 1
J 0
(-4775 6875);
DISPLAY INVISIBLE (-4775 6875);
FORCEPROP 1 LASTPIN (-4825 6800) $PN 1
J 0
(-4820 6762);
DISPLAY 0.787234 (-4820 6762);
PAINT MONO (-4820 6762);
DISPLAY INVISIBLE (-4820 6762);
FORCEPROP 1 LASTPIN (-4825 6600) $PN 2
J 0
(-4820 6610);
DISPLAY 0.787234 (-4820 6610);
PAINT MONO (-4820 6610);
DISPLAY INVISIBLE (-4820 6610);
FORCEADD DNS..1
(-4750 1875);
PAINT RED (-4750 1875);
FORCEPROP 1 LAST COMMENT_BODY TRUE
R 1
J 0
(-4675 1650);
DISPLAY 0.872340 (-4675 1650);
PAINT GREEN (-4675 1650);
DISPLAY INVISIBLE (-4675 1650);
FORCEPROP 2 LAST CDS_LIB mstr_misc
J 0
(-4750 1875);
PAINT MONO (-4750 1875);
DISPLAY INVISIBLE (-4750 1875);
FORCEADD DNS..1
(-4725 4725);
PAINT RED (-4725 4725);
FORCEPROP 1 LAST COMMENT_BODY TRUE
R 1
J 0
(-4650 4500);
DISPLAY 0.872340 (-4650 4500);
PAINT GREEN (-4650 4500);
DISPLAY INVISIBLE (-4650 4500);
FORCEPROP 2 LAST CDS_LIB mstr_misc
J 0
(-4725 4725);
PAINT MONO (-4725 4725);
DISPLAY INVISIBLE (-4725 4725);
FORCEADD DNS..1
(-4125 3875);
PAINT RED (-4125 3875);
FORCEPROP 1 LAST COMMENT_BODY TRUE
R 1
J 0
(-4050 3650);
DISPLAY 0.872340 (-4050 3650);
PAINT GREEN (-4050 3650);
DISPLAY INVISIBLE (-4050 3650);
FORCEPROP 2 LAST CDS_LIB mstr_misc
J 0
(-4125 3875);
DISPLAY INVISIBLE (-4125 3875);
FORCEADD DNS..1
(-4125 6675);
PAINT RED (-4125 6675);
FORCEPROP 1 LAST COMMENT_BODY TRUE
R 1
J 0
(-4050 6450);
DISPLAY 0.872340 (-4050 6450);
PAINT GREEN (-4050 6450);
DISPLAY INVISIBLE (-4050 6450);
FORCEPROP 2 LAST CDS_LIB mstr_misc
J 0
(-4125 6675);
DISPLAY INVISIBLE (-4125 6675);
FORCEADD QUANTA_TITLE_BLOCK_C..1
(3700 900);
FORCEPROP 0 LAST CDS_CON_LAST_MODIFIED Fri Aug 25 14:04:42 2023
J 0
(1815 915);
DISPLAY INVISIBLE (1815 915);
FORCEPROP 1 LAST CUSTOM_TXT_CDS <CON_LAST_MODIFIED>
J 0
(1815 915);
DISPLAY 0.978723 (1815 915);
FORCEPROP 2 LAST CUSTOM_TXT_CDS <XR_PAGE_TITLE>
J 0
(-4190 6150);
DISPLAY 0.638298 (-4190 6150);
PAINT PINK (-4190 6150);
DISPLAY INVISIBLE (-4190 6150);
FORCEPROP 1 LAST CUSTOM_TXT_CDS <NAME_2>
J 0
(525 950);
FORCEPROP 1 LAST CUSTOM_TXT_CDS <NAME_1>
J 0
(525 1075);
FORCEPROP 1 LAST CUSTOM_TXT_CDS <Q_NUMBER>
J 0
(2297 1003);
DISPLAY 1.212766 (2297 1003);
FORCEPROP 1 LAST CUSTOM_TXT_CDS <Q_PROJ>
J 0
(1318 1002);
DISPLAY 1.212766 (1318 1002);
FORCEPROP 1 LAST CUSTOM_TXT_CDS <Q_REV>
J 0
(3516 1003);
DISPLAY 1.212766 (3516 1003);
FORCEPROP 1 LAST CUSTOM_TXT_CDS <CON_PAGE_NUM> OF <CON_TOTAL_PAGES>
J 0
(3254 918);
DISPLAY 0.978723 (3254 918);
FORCEPROP 1 LAST Q_TITLE VCCFA_EHV_FIVRA CPU0 VR PHASE 1&2(6/7)
J 0
(-5600 950);
DISPLAY 2.446809 (-5600 950);
PAINT GREEN (-5600 950);
FORCEPROP 1 LAST Q_DEPT 
J 1
(-63 949);
DISPLAY 1.957447 (-63 949);
PAINT GREEN (-63 949);
FORCEPROP 2 LAST CDS_XR_PAGE_TITLE CR-271 : @S9S_MB_2U_LIB.S9S_MB_2U(SCH_1):PAGE271
J 0
(-4190 6150);
DISPLAY 0.638298 (-4190 6150);
PAINT PINK (-4190 6150);
DISPLAY INVISIBLE (-4190 6150);
FORCEPROP 2 LAST CDS_LIB pure_quanta
J 0
(3700 900);
DISPLAY INVISIBLE (3700 900);
FORCEPROP 1 LAST CDS_LMAN_SYM_OUTLINE -9475,6775,100,-125
J 0
(3700 900);
DISPLAY 0.468085 (3700 900);
PAINT GREEN (3700 900);
DISPLAY INVISIBLE (3700 900);
FORCEPROP 2 LAST PAGE_BORDER TRUE
J 0
(-4190 6150);
DISPLAY 0.638298 (-4190 6150);
PAINT PINK (-4190 6150);
DISPLAY INVISIBLE (-4190 6150);
FORCEPROP 1 LAST COMMENT_BODY TRUE
J 0
(3712 887);
DISPLAY 0.978723 (3712 887);
PAINT GREEN (3712 887);
DISPLAY INVISIBLE (3712 887);
WIRE 16 -1 (-4825 4075)(-4825 4000);
WIRE 16 -1 (-4825 6875)(-4825 6800);
WIRE 16 -1 (-4175 4075)(-4175 4000);
WIRE 16 -1 (-4175 6875)(-4175 6800);
WIRE 16 -1 (-125 3625)(-125 3550);
WIRE 16 -1 (2700 2575)(2700 2400);
WIRE 16 -1 (3175 3600)(3175 3550);
WIRE 16 -1 (-125 6425)(-125 6350);
WIRE 16 -1 (1000 6200)(1000 6075);
WIRE 16 -1 (2175 5350)(2175 5200);
WIRE 16 -1 (3025 6175)(3025 6075);
WIRE 16 -1 (-4750 1800)(-4750 1725);
WIRE 16 -1 (-4800 2200)(-4800 2175);
WIRE 16 -1 (-4800 2200)(-4075 2200);
WIRE 16 -1 (-4725 4650)(-4725 4575);
WIRE 16 -1 (-4800 5000)(-4800 4975);
WIRE 16 -1 (-4800 5000)(-4075 5000);
WIRE 16 -1 (-4250 2750)(-4250 2650);
WIRE 16 -1 (-3725 3150)(-3725 3050);
WIRE 16 -1 (-2075 1800)(-2075 1725);
WIRE 16 -1 (-2075 1850)(-2075 1800);
WIRE 16 -1 (-2325 1800)(-2075 1800);
WIRE 16 -1 (-2075 4600)(-2075 4525);
WIRE 16 -1 (-2075 4650)(-2075 4600);
WIRE 16 -1 (-2325 4600)(-2075 4600);
WIRE 16 -1 (-4250 5550)(-4250 5450);
WIRE 16 -1 (-3725 5950)(-3725 5850);
WIRE 16 -1 (-125 2975)(-125 3050);
WIRE 16 -1 (2700 1825)(2700 1975);
WIRE 16 -1 (2175 4675)(2175 4775);
WIRE 16 -1 (3175 3125)(3175 3025);
WIRE 16 -1 (2725 3125)(3175 3125);
WIRE 16 -1 (3175 3225)(3175 3125);
WIRE 16 -1 (-125 5775)(-125 5850);
WIRE 16 -1 (1000 5675)(1000 5775);
WIRE 16 -1 (2900 5650)(2900 5625);
WIRE 16 -1 (2625 5650)(2900 5650);
WIRE 16 -1 (2900 5750)(2900 5650);
WIRE 16 -1 (2725 3225)(2725 3125);
WIRE 16 -1 (2225 3225)(2225 3125);
WIRE 16 -1 (2725 3125)(2225 3125);
WIRE 16 -1 (1700 3125)(1700 3225);
WIRE 16 -1 (1700 3125)(2225 3125);
WIRE 16 -1 (1175 3125)(1700 3125);
WIRE 16 -1 (1175 3225)(1175 3125);
WIRE 16 -1 (3175 3550)(3175 3425);
WIRE 16 -1 (2725 3425)(2725 3550);
WIRE 16 -1 (2725 3550)(3175 3550);
WIRE 16 -1 (2225 3425)(2225 3550);
WIRE 16 -1 (2725 3550)(2225 3550);
WIRE 16 -1 (1700 3550)(1700 3425);
WIRE 16 -1 (1700 3550)(2225 3550);
WIRE 16 -1 (1175 3550)(1700 3550);
WIRE 16 -1 (1175 3425)(1175 3550);
WIRE 16 -1 (2625 5750)(2625 5650);
WIRE 16 -1 (2350 5750)(2350 5650);
WIRE 16 -1 (2350 5650)(2625 5650);
WIRE 16 -1 (2075 5750)(2075 5650);
WIRE 16 -1 (2075 5650)(2350 5650);
WIRE 16 -1 (1775 5650)(2075 5650);
WIRE 16 -1 (1775 5750)(1775 5650);
WIRE 16 -1 (3025 6075)(2900 6075);
WIRE 16 -1 (2900 6075)(2900 5950);
WIRE 16 -1 (2625 5950)(2625 6075);
WIRE 16 -1 (2900 6075)(2625 6075);
WIRE 16 -1 (2350 5950)(2350 6075);
WIRE 16 -1 (2625 6075)(2350 6075);
WIRE 16 -1 (2075 5950)(2075 6075);
WIRE 16 -1 (2350 6075)(2075 6075);
WIRE 16 -1 (1775 5950)(1775 6075);
WIRE 16 -1 (2075 6075)(1775 6075);
WIRE 16 -1 (1525 6075)(1775 6075);
WIRE 16 -1 (-3175 5350)(-3325 5350);
WIRE 16 -1 (-3325 5550)(-3325 5350);
WIRE 16 -1 (-3175 5550)(-3325 5550);
WIRE 16 -1 (-3325 5550)(-4000 5550);
FORCEPROP 0 LAST CDS_PHYS_NET_NAME PVCCFA_EHV_FIVRA_CPU0_VDD1
J 0
(-3935 5590);
PAINT MONO (-3935 5590);
DISPLAY INVISIBLE (-3935 5590);
FORCEPROP 2 LAST SIG_NAME PVCCFA_EHV_FIVRA_CPU0_VDD1
J 0
(-3960 5560);
DISPLAY 0.617021 (-3960 5560);
WIRE 16 -1 (-4000 5550)(-4000 5850);
WIRE 16 -1 (-4250 5850)(-4250 5950);
WIRE 16 -1 (-4000 5850)(-4250 5850);
WIRE 16 -1 (-4250 5750)(-4250 5850);
WIRE 16 -1 (1875 5100)(1875 5200);
WIRE 16 -1 (2175 5200)(1875 5200);
WIRE 16 -1 (250 4950)(75 4950);
WIRE 16 -1 (1450 5200)(1450 5100);
WIRE 16 -1 (1450 5200)(1875 5200);
WIRE 16 -1 (950 5100)(950 5200);
WIRE 16 -1 (1450 5200)(950 5200);
WIRE 16 -1 (250 5200)(250 4950);
WIRE 16 -1 (250 5200)(75 5200);
WIRE 16 -1 (250 5200)(950 5200);
WIRE 16 -1 (1875 4900)(1875 4775);
WIRE 16 -1 (2175 4775)(1875 4775);
WIRE 16 -1 (1450 4775)(1450 4900);
WIRE 16 -1 (1875 4775)(1450 4775);
WIRE 16 -1 (1450 4775)(950 4775);
WIRE 16 -1 (950 4900)(950 4775);
WIRE 16 -1 (1000 6075)(1325 6075);
WIRE 16 -1 (1000 5975)(1000 6075);
WIRE 16 -1 (-300 6350)(-300 6225);
WIRE 16 -1 (-125 6350)(-300 6350);
WIRE 16 -1 (-725 6200)(-725 6350);
WIRE 16 -1 (-300 6350)(-725 6350);
WIRE 16 -1 (-1125 6350)(-1125 6200);
WIRE 16 -1 (-1125 6350)(-725 6350);
WIRE 16 -1 (-2150 5800)(-2325 5800);
WIRE 16 -1 (-2325 5850)(-2150 5850);
WIRE 16 -1 (-2150 5850)(-2150 5800);
WIRE 16 -1 (-1525 6200)(-1525 6350);
WIRE 16 -1 (-1525 6350)(-1125 6350);
WIRE 16 -1 (-1925 6200)(-1925 6350);
WIRE 16 -1 (-1925 6350)(-1525 6350);
WIRE 16 -1 (-2150 6350)(-2150 5850);
WIRE 16 -1 (-2150 6350)(-1925 6350);
WIRE 16 -1 (-300 6025)(-300 5850);
WIRE 16 -1 (-125 5850)(-300 5850);
WIRE 16 -1 (-725 6000)(-725 5850);
WIRE 16 -1 (-300 5850)(-725 5850);
WIRE 16 -1 (-1125 6000)(-1125 5850);
WIRE 16 -1 (-1125 5850)(-725 5850);
WIRE 16 -1 (-1525 6000)(-1525 5850);
WIRE 16 -1 (-1125 5850)(-1525 5850);
WIRE 16 -1 (-1925 5850)(-1525 5850);
WIRE 16 -1 (-1925 6000)(-1925 5850);
WIRE 16 -1 (2300 2400)(2300 2300);
WIRE 16 -1 (2700 2400)(2300 2400);
WIRE 16 -1 (1875 2300)(1875 2400);
WIRE 16 -1 (2300 2400)(1875 2400);
WIRE 16 -1 (250 2150)(75 2150);
WIRE 16 -1 (1450 2400)(1450 2300);
WIRE 16 -1 (1450 2400)(1875 2400);
WIRE 16 -1 (1000 2300)(1000 2400);
WIRE 16 -1 (1450 2400)(1000 2400);
WIRE 16 -1 (250 2400)(250 2150);
WIRE 16 -1 (75 2400)(250 2400);
WIRE 16 -1 (250 2400)(1000 2400);
WIRE 16 -1 (2700 1975)(2300 1975);
WIRE 16 -1 (2300 2100)(2300 1975);
WIRE 16 -1 (1875 2100)(1875 1975);
WIRE 16 -1 (2300 1975)(1875 1975);
WIRE 16 -1 (1875 1975)(1450 1975);
WIRE 16 -1 (1450 1975)(1450 2100);
WIRE 16 -1 (1000 1975)(1450 1975);
WIRE 16 -1 (1000 2100)(1000 1975);
WIRE 16 -1 (-125 3550)(-250 3550);
WIRE 16 -1 (-250 3400)(-250 3550);
WIRE 16 -1 (-725 3400)(-725 3550);
WIRE 16 -1 (-250 3550)(-725 3550);
WIRE 16 -1 (-1125 3550)(-1125 3400);
WIRE 16 -1 (-1125 3550)(-725 3550);
WIRE 16 -1 (-2150 3000)(-2325 3000);
WIRE 16 -1 (-2325 3050)(-2150 3050);
WIRE 16 -1 (-2150 3050)(-2150 3000);
WIRE 16 -1 (-1525 3400)(-1525 3550);
WIRE 16 -1 (-1525 3550)(-1125 3550);
WIRE 16 -1 (-1925 3400)(-1925 3550);
WIRE 16 -1 (-1925 3550)(-1525 3550);
WIRE 16 -1 (-2150 3550)(-2150 3050);
WIRE 16 -1 (-2150 3550)(-1925 3550);
WIRE 16 -1 (-125 3050)(-250 3050);
WIRE 16 -1 (-250 3200)(-250 3050);
WIRE 16 -1 (-250 3050)(-725 3050);
WIRE 16 -1 (-725 3200)(-725 3050);
WIRE 16 -1 (-1125 3200)(-1125 3050);
WIRE 16 -1 (-1125 3050)(-725 3050);
WIRE 16 -1 (-1125 3050)(-1525 3050);
WIRE 16 -1 (-1525 3200)(-1525 3050);
WIRE 16 -1 (-1925 3050)(-1525 3050);
WIRE 16 -1 (-1925 3200)(-1925 3050);
WIRE 16 -1 (-2325 2400)(-125 2400);
FORCEPROP 2 LAST SIG_NAME SW_PVCCFA_EHV_FIVRA_CPU0_SW2
J 0
(-2135 2410);
DISPLAY 0.617021 (-2135 2410);
WIRE 16 -1 (-300 2500)(-300 2575);
WIRE 16 -1 (-2325 2500)(-300 2500);
FORCEPROP 2 LAST SIG_NAME SW_PVCCFA_EHV_FIVRA_CPU0_BOOTR2
J 0
(-2135 2510);
DISPLAY 0.617021 (-2135 2510);
WIRE 16 -1 (-300 2850)(-300 2775);
WIRE 16 -1 (-1125 2850)(-300 2850);
FORCEPROP 2 LAST SIG_NAME SW_PVCCFA_EHV_FIVRA_CPU0_BOOT2_R
J 0
(-835 2860);
DISPLAY 0.617021 (-835 2860);
WIRE 16 -1 (-2325 4950)(-125 4950);
FORCEPROP 2 LAST SIG_NAME PVCCFA_EHV_FIVRA_CPU0_VOS1
J 0
(-2123 4975);
DISPLAY 0.617021 (-2123 4975);
WIRE 16 -1 (-300 5650)(-300 5575);
WIRE 16 -1 (-1125 5650)(-300 5650);
FORCEPROP 2 LAST SIG_NAME SW_PVCCFA_EHV_FIVRA_CPU0_BOOT1_R
J 0
(-835 5660);
DISPLAY 0.617021 (-835 5660);
WIRE 16 -1 (-2325 5200)(-125 5200);
FORCEPROP 2 LAST SIG_NAME SW_PVCCFA_EHV_FIVRA_CPU0_SW1
J 0
(-2135 5210);
DISPLAY 0.617021 (-2135 5210);
WIRE 16 -1 (-2325 2150)(-125 2150);
FORCEPROP 2 LAST SIG_NAME PVCCFA_EHV_FIVRA_CPU0_VOS2
J 0
(-2123 2150);
DISPLAY 0.617021 (-2123 2150);
WIRE 16 -1 (-300 5300)(-300 5375);
WIRE 16 -1 (-2325 5300)(-300 5300);
FORCEPROP 2 LAST SIG_NAME SW_PVCCFA_EHV_FIVRA_CPU0_BOOTR1
J 0
(-2135 5310);
DISPLAY 0.617021 (-2135 5310);
WIRE 16 -1 (-2175 5650)(-1325 5650);
WIRE 16 -1 (-2175 5550)(-2175 5650);
FORCEPROP 2 LAST SIG_NAME SW_PVCCFA_EHV_FIVRA_CPU0_BOOT1
J 0
(-2385 5660);
DISPLAY 0.617021 (-2385 5660);
WIRE 16 -1 (-2325 5550)(-2175 5550);
WIRE 16 -1 (-2075 4750)(-2325 4750);
WIRE 16 -1 (-2325 4700)(-2075 4700);
WIRE 16 -1 (-2075 4700)(-2075 4750);
WIRE 16 -1 (-2075 4700)(-2075 4650);
WIRE 16 -1 (-2325 4650)(-2075 4650);
WIRE 16 -1 (-3325 5850)(-3175 5850);
WIRE 16 -1 (-3325 5850)(-3325 6250);
WIRE 16 -1 (-3725 6150)(-3725 6250);
WIRE 16 -1 (-3325 6250)(-3725 6250);
WIRE 16 -1 (-4175 6600)(-4175 6250);
WIRE 16 -1 (-3725 6250)(-4175 6250);
FORCEPROP 2 LAST SIG_NAME PVCCFA_EHV_FIVRA_CPU0_PVCC1
J 0
(-4110 6260);
DISPLAY 0.617021 (-4110 6260);
WIRE 16 -1 (-4250 6250)(-4250 6150);
WIRE 16 -1 (-4175 6250)(-4250 6250);
WIRE 16 -1 (-4825 6250)(-4250 6250);
WIRE 16 -1 (-4825 6600)(-4825 6250);
WIRE 16 -1 (-3325 5000)(-3875 5000);
WIRE 16 -1 (-4200 5100)(-3325 5100);
FORCEPROP 2 LAST SIG_NAME PVCCIN_CPU0_VREF
J 0
(-4135 5110);
DISPLAY 0.617021 (-4135 5110);
WIRE 16 -1 (-3325 5100)(-3175 5100);
WIRE 16 -1 (-3325 5100)(-3325 5000);
FORCEPROP 0 LAST CDS_PHYS_NET_NAME PVCCIN_CPU0_VREF
J 0
(-3325 5025);
PAINT MONO (-3325 5025);
DISPLAY INVISIBLE (-3325 5025);
WIRE 16 -1 (-3175 5200)(-4200 5200);
FORCEPROP 2 LAST SIG_NAME PVCCFA_EHV_FIVRA_CPU0_IMON1
J 0
(-4135 5210);
DISPLAY 0.617021 (-4135 5210);
WIRE 16 -1 (-3175 4700)(-4200 4700);
FORCEPROP 2 LAST SIG_NAME PVCCFA_EHV_FIVRA_CPU0_BTSEN
J 0
(-4135 4710);
DISPLAY 0.617021 (-4135 4710);
WIRE 16 -1 (-2175 2850)(-1325 2850);
WIRE 16 -1 (-2175 2750)(-2175 2850);
FORCEPROP 2 LAST SIG_NAME SW_PVCCFA_EHV_FIVRA_CPU0_BOOT2
J 0
(-2410 2860);
DISPLAY 0.617021 (-2410 2860);
WIRE 16 -1 (-2325 2750)(-2175 2750);
WIRE 16 -1 (-2075 1950)(-2325 1950);
WIRE 16 -1 (-2325 1900)(-2075 1900);
WIRE 16 -1 (-2075 1900)(-2075 1950);
WIRE 16 -1 (-2075 1900)(-2075 1850);
WIRE 16 -1 (-2325 1850)(-2075 1850);
WIRE 16 -1 (-3325 3050)(-3175 3050);
WIRE 16 -1 (-3325 3050)(-3325 3450);
WIRE 16 -1 (-3725 3350)(-3725 3450);
WIRE 16 -1 (-3325 3450)(-3725 3450);
WIRE 16 -1 (-4175 3800)(-4175 3450);
WIRE 16 -1 (-3725 3450)(-4175 3450);
FORCEPROP 2 LAST SIG_NAME PVCCFA_EHV_FIVRA_CPU0_PVCC2
J 0
(-4110 3460);
DISPLAY 0.617021 (-4110 3460);
WIRE 16 -1 (-4250 3450)(-4250 3350);
WIRE 16 -1 (-4175 3450)(-4250 3450);
WIRE 16 -1 (-4825 3450)(-4250 3450);
WIRE 16 -1 (-4825 3800)(-4825 3450);
WIRE 16 -1 (-3175 4600)(-4200 4600);
FORCEPROP 2 LAST SIG_NAME PVCCFA_EHV_FIVRA_CPU0_PWM1
J 0
(-4135 4610);
DISPLAY 0.617021 (-4135 4610);
WIRE 16 -1 (-3175 2550)(-3325 2550);
WIRE 16 -1 (-3325 2750)(-3325 2550);
WIRE 16 -1 (-3175 2750)(-3325 2750);
WIRE 16 -1 (-3325 2750)(-4000 2750);
FORCEPROP 0 LAST CDS_PHYS_NET_NAME PVCCFA_EHV_FIVRA_CPU0_VDD2
J 0
(-3935 2790);
PAINT MONO (-3935 2790);
DISPLAY INVISIBLE (-3935 2790);
FORCEPROP 2 LAST SIG_NAME PVCCFA_EHV_FIVRA_CPU0_VDD2
J 0
(-3960 2760);
DISPLAY 0.617021 (-3960 2760);
WIRE 16 -1 (-4000 2750)(-4000 3050);
WIRE 16 -1 (-4250 3050)(-4250 3150);
WIRE 16 -1 (-4000 3050)(-4250 3050);
WIRE 16 -1 (-4250 2950)(-4250 3050);
WIRE 16 -1 (-3325 2200)(-3875 2200);
WIRE 16 -1 (-4225 2300)(-3325 2300);
FORCEPROP 2 LAST SIG_NAME PVCCIN_CPU0_VREF
J 0
(-4160 2310);
DISPLAY 0.617021 (-4160 2310);
WIRE 16 -1 (-3325 2300)(-3175 2300);
WIRE 16 -1 (-3325 2300)(-3325 2200);
FORCEPROP 0 LAST CDS_PHYS_NET_NAME PVCCIN_CPU0_VREF
J 0
(-3325 2225);
PAINT MONO (-3325 2225);
DISPLAY INVISIBLE (-3325 2225);
WIRE 16 -1 (-3175 2400)(-4225 2400);
FORCEPROP 2 LAST SIG_NAME PVCCFA_EHV_FIVRA_CPU0_IMON2
J 0
(-4160 2410);
DISPLAY 0.617021 (-4160 2410);
WIRE 16 -1 (-3175 1900)(-4225 1900);
FORCEPROP 2 LAST SIG_NAME PVCCFA_EHV_FIVRA_CPU0_BTSEN
J 0
(-4160 1910);
DISPLAY 0.617021 (-4160 1910);
WIRE 16 -1 (-3175 1800)(-4225 1800);
FORCEPROP 2 LAST SIG_NAME PVCCFA_EHV_FIVRA_CPU0_PWM2
J 0
(-4160 1810);
DISPLAY 0.617021 (-4160 1810);
WIRE 16 -1 (-4725 4900)(-4725 4850);
WIRE 16 -1 (-4725 4900)(-3175 4900);
FORCEPROP 0 LAST CDS_PHYS_NET_NAME PVCCFA_EHV_FIVRA_CPU0_LSET1
J 0
(-4135 4940);
PAINT MONO (-4135 4940);
DISPLAY INVISIBLE (-4135 4940);
FORCEPROP 2 LAST SIG_NAME PVCCFA_EHV_FIVRA_CPU0_LSET1
J 0
(-4135 4910);
DISPLAY 0.617021 (-4135 4910);
WIRE 16 -1 (-4750 2100)(-4750 2000);
WIRE 16 -1 (-4750 2100)(-3175 2100);
FORCEPROP 2 LAST SIG_NAME PVCCFA_EHV_FIVRA_CPU0_LSET2
J 0
(-4160 2110);
DISPLAY 0.617021 (-4160 2110);
DOT 1 (-3325 2300);
DOT 1 (-4250 3050);
DOT 1 (-4250 3450);
DOT 1 (-4175 3450);
DOT 1 (-3725 3450);
DOT 1 (-3325 2750);
DOT 1 (-2075 1800);
DOT 1 (-2075 1900);
DOT 1 (-2075 1850);
DOT 1 (-2150 3050);
DOT 1 (-1925 3550);
DOT 1 (-1525 3050);
DOT 1 (-1525 3550);
DOT 1 (-2075 4600);
DOT 1 (-1125 3050);
DOT 1 (-1125 3550);
DOT 1 (-725 3050);
DOT 1 (-725 3550);
DOT 1 (-4250 5850);
DOT 1 (-4250 6250);
DOT 1 (-4175 6250);
DOT 1 (-3725 6250);
DOT 1 (-3325 5100);
DOT 1 (-3325 5550);
DOT 1 (-2075 4700);
DOT 1 (-2075 4650);
DOT 1 (-2150 5850);
DOT 1 (-1925 6350);
DOT 1 (-1525 5850);
DOT 1 (-1525 6350);
DOT 1 (-1125 5850);
DOT 1 (-1125 6350);
DOT 1 (-725 5850);
DOT 1 (-725 6350);
DOT 1 (250 2400);
DOT 1 (1000 2400);
DOT 1 (1450 1975);
DOT 1 (1450 2400);
DOT 1 (-250 3050);
DOT 1 (-250 3550);
DOT 1 (1875 1975);
DOT 1 (1875 2400);
DOT 1 (2300 1975);
DOT 1 (2300 2400);
DOT 1 (1700 3125);
DOT 1 (1700 3550);
DOT 1 (2225 3125);
DOT 1 (2225 3550);
DOT 1 (2725 3125);
DOT 1 (2725 3550);
DOT 1 (3175 3125);
DOT 1 (3175 3550);
DOT 1 (250 5200);
DOT 1 (-300 5850);
DOT 1 (-300 6350);
DOT 1 (950 5200);
DOT 1 (1450 4775);
DOT 1 (1450 5200);
DOT 1 (1000 6075);
DOT 1 (1875 4775);
DOT 1 (1875 5200);
DOT 1 (2075 5650);
DOT 1 (2350 5650);
DOT 1 (2625 5650);
DOT 1 (1775 6075);
DOT 1 (2075 6075);
DOT 1 (2350 6075);
DOT 1 (2625 6075);
DOT 1 (2900 5650);
DOT 1 (2900 6075);
FORCENOTE
PVCCFA_EHV_FIVRA_CPU0_PHASE2
(-3525 3575) 0;
DISPLAY LEFT (-3525 3575);
DISPLAY 1.021277 (-3525 3575);
PAINT WHITE (-3525 3575);
FORCENOTE
20211013 MODIFY FOR GT
(-5525 7350) 0;
DISPLAY LEFT (-5525 7350);
DISPLAY 1.595745 (-5525 7350);
PAINT PINK (-5525 7350);
FORCENOTE
PVCCFA_EHV_FIVRA_CPU0_PHASE1
(-3525 6375) 0;
DISPLAY LEFT (-3525 6375);
DISPLAY 1.021277 (-3525 6375);
PAINT WHITE (-3525 6375);
FORCENOTE
ISAT = 90A @ 100C
(350 2525) 0;
DISPLAY LEFT (350 2525);
DISPLAY 1.021277 (350 2525);
FORCENOTE
DCR = 0.103M OHM
(350 2450) 0;
DISPLAY LEFT (350 2450);
DISPLAY 1.021277 (350 2450);
FORCENOTE
PG2323.131HLT
(350 2675) 0;
DISPLAY LEFT (350 2675);
DISPLAY 1.021277 (350 2675);
FORCENOTE
10.0*7.5*12.0
(350 2600) 0;
DISPLAY LEFT (350 2600);
DISPLAY 1.021277 (350 2600);
FORCENOTE
APPLY TO ALL RAILS.
(1225 1475) 0;
DISPLAY LEFT (1225 1475);
DISPLAY 1.021277 (1225 1475);
FORCENOTE
RENESAS RECOMMEND BLEEDER RESISTOR
(1225 1625) 0;
DISPLAY LEFT (1225 1625);
DISPLAY 1.021277 (1225 1625);
FORCENOTE
(499OHM) TO ABSORB LEAKAGE FROM SPS.
(1225 1550) 0;
DISPLAY LEFT (1225 1550);
DISPLAY 1.021277 (1225 1550);
FORCENOTE
PG2323.131HLT
(400 5475) 0;
DISPLAY LEFT (400 5475);
DISPLAY 1.021277 (400 5475);
FORCENOTE
10.0*7.5*12.0
(400 5400) 0;
DISPLAY LEFT (400 5400);
DISPLAY 1.021277 (400 5400);
FORCENOTE
DCR = 0.103M OHM
(400 5250) 0;
DISPLAY LEFT (400 5250);
DISPLAY 1.021277 (400 5250);
FORCENOTE
ISAT = 90A @ 100C
(400 5325) 0;
DISPLAY LEFT (400 5325);
DISPLAY 1.021277 (400 5325);
FORCENOTE
4.5*4.5*4.5
(1600 6300) 0;
DISPLAY LEFT (1600 6300);
DISPLAY 0.808511 (1600 6300);
FORCENOTE
HCBS4545-101
(1600 6375) 0;
DISPLAY LEFT (1600 6375);
DISPLAY 0.808511 (1600 6375);
FORCENOTE
ISAT = 13A @ 100C
(1600 6225) 0;
DISPLAY LEFT (1600 6225);
DISPLAY 0.808511 (1600 6225);
FORCENOTE
DCR = 0.12M OHM
(1600 6150) 0;
DISPLAY LEFT (1600 6150);
DISPLAY 0.808511 (1600 6150);
FORCENOTE
ESR=9.5M OHM
(2950 5625) 0;
DISPLAY LEFT (2950 5625);
DISPLAY 0.638298 (2950 5625);
QUIT
